G04*
G04 #@! TF.GenerationSoftware,Altium Limited,Altium Designer,23.7.1 (13)*
G04*
G04 Layer_Color=65535*
%FSLAX25Y25*%
%MOIN*%
G70*
G04*
G04 #@! TF.SameCoordinates,AF00DCEB-AC48-4C7C-91EA-99F42E284231*
G04*
G04*
G04 #@! TF.FilePolarity,Positive*
G04*
G01*
G75*
%ADD10C,0.00984*%
%ADD11C,0.02000*%
%ADD12C,0.01968*%
%ADD13C,0.01575*%
%ADD14C,0.01575*%
%ADD15C,0.00787*%
%ADD16C,0.00500*%
%ADD17C,0.01500*%
%ADD18C,0.01000*%
%ADD19C,0.00600*%
%ADD20C,0.00300*%
%ADD21C,0.00100*%
%ADD22C,0.00591*%
%ADD23C,0.00394*%
%ADD24C,0.00900*%
%ADD25C,0.00800*%
%ADD26R,0.29528X0.28543*%
%ADD27R,0.17717X0.59055*%
%ADD28R,0.28543X0.29528*%
%ADD29R,0.50197X0.35236*%
%ADD30R,0.59055X0.17717*%
G36*
X88157Y-20829D02*
Y-19329D01*
X87157D01*
Y-20829D01*
X88157D01*
D02*
G37*
G36*
X112958Y-8230D02*
Y-6730D01*
X113958D01*
Y-8230D01*
X112958D01*
D02*
G37*
G36*
X159087Y159D02*
X160087D01*
Y-1341D01*
X159087D01*
Y159D01*
D02*
G37*
G36*
X486647Y-304171D02*
X487646D01*
Y-305671D01*
X486647D01*
Y-304171D01*
D02*
G37*
G36*
X427597Y-128443D02*
X429097D01*
Y-129443D01*
X427597D01*
Y-128443D01*
D02*
G37*
G36*
X414998Y-103643D02*
X416498D01*
Y-102643D01*
X414998D01*
Y-103643D01*
D02*
G37*
D10*
X72481Y-113967D02*
G03*
X72481Y-113967I-492J0D01*
G01*
X576083Y18898D02*
G03*
X576083Y18898I-492J0D01*
G01*
X437598Y-130807D02*
G03*
X437598Y-130807I-492J0D01*
G01*
X157087Y-99990D02*
G03*
X157087Y-99990I-492J0D01*
G01*
X605217Y-285138D02*
G03*
X605217Y-285138I-492J0D01*
G01*
X594587Y-233071D02*
G03*
X594587Y-233071I-492J0D01*
G01*
X596752Y-186107D02*
G03*
X596752Y-186107I-492J0D01*
G01*
X625689Y-216535D02*
G03*
X625689Y-216535I-492J0D01*
G01*
X624902Y-180315D02*
G03*
X624902Y-180315I-492J0D01*
G01*
X591437Y-150000D02*
G03*
X591437Y-150000I-492J0D01*
G01*
X474606Y-262598D02*
G03*
X474606Y-262598I-492J0D01*
G01*
X187106Y-100689D02*
G03*
X187106Y-100689I-492J0D01*
G01*
X169193Y-75492D02*
G03*
X169193Y-75492I-492J0D01*
G01*
X572835Y-297539D02*
G03*
X572835Y-297539I-492J0D01*
G01*
X174544Y-117717D02*
G03*
X174544Y-117717I-492J0D01*
G01*
X432533Y-188148D02*
G03*
X432533Y-188148I-492J0D01*
G01*
X373575Y-160827D02*
G03*
X373575Y-160827I-492J0D01*
G01*
X40020Y-43355D02*
G03*
X40020Y-43355I-492J0D01*
G01*
X47638Y-34547D02*
G03*
X47638Y-34547I-492J0D01*
G01*
X448327Y-76378D02*
G03*
X448327Y-76378I-492J0D01*
G01*
X102461Y-92126D02*
G03*
X102461Y-92126I-492J0D01*
G01*
X594587Y-220472D02*
G03*
X594587Y-220472I-492J0D01*
G01*
X279232Y-201476D02*
G03*
X279232Y-201476I-492J0D01*
G01*
X220354Y-132283D02*
G03*
X220354Y-132283I-492J0D01*
G01*
X196339Y-131299D02*
G03*
X196339Y-131299I-492J0D01*
G01*
X420024Y-350124D02*
G03*
X420024Y-350124I-492J0D01*
G01*
X464807Y-350911D02*
G03*
X464807Y-350911I-492J0D01*
G01*
X503228Y-350588D02*
G03*
X503228Y-350588I-492J0D01*
G01*
X548209Y-350391D02*
G03*
X548209Y-350391I-492J0D01*
G01*
X594587Y-226772D02*
G03*
X594587Y-226772I-492J0D01*
G01*
X13973Y-203630D02*
G03*
X13973Y-203630I-492J0D01*
G01*
X319882Y-236614D02*
G03*
X319882Y-236614I-492J0D01*
G01*
X622795Y-360807D02*
G03*
X622795Y-360807I-492J0D01*
G01*
X22539Y-1969D02*
G03*
X22539Y-1969I-492J0D01*
G01*
Y4921D02*
G03*
X22539Y4921I-492J0D01*
G01*
Y11811D02*
G03*
X22539Y11811I-492J0D01*
G01*
Y18701D02*
G03*
X22539Y18701I-492J0D01*
G01*
X611319Y-250397D02*
G03*
X611319Y-250397I-492J0D01*
G01*
X333661Y-289764D02*
G03*
X333661Y-289764I-492J0D01*
G01*
X314764Y-290551D02*
G03*
X314764Y-290551I-492J0D01*
G01*
X584154Y-64567D02*
G03*
X584154Y-64567I-492J0D01*
G01*
X598898Y-88779D02*
G03*
X598898Y-88779I-492J0D01*
G01*
X13973Y-255795D02*
G03*
X13973Y-255795I-492J0D01*
G01*
X13973Y-150332D02*
G03*
X13973Y-150332I-492J0D01*
G01*
X13973Y-309929D02*
G03*
X13973Y-309929I-492J0D01*
G01*
X136150Y-135633D02*
G03*
X136150Y-135633I-492J0D01*
G01*
D11*
X122649Y-73277D02*
G03*
X122649Y-73277I-100J0D01*
G01*
X560878Y-335915D02*
G03*
X560878Y-335915I-100J0D01*
G01*
X242126Y-158661D02*
X291339D01*
X242126Y-122835D02*
X291339D01*
Y-158661D02*
Y-122835D01*
X242126Y-158661D02*
Y-122835D01*
D12*
X374776Y-147736D02*
G03*
X374776Y-147736I-984J0D01*
G01*
X53602Y-44064D02*
G03*
X53602Y-44064I-984J0D01*
G01*
X600098Y-75689D02*
G03*
X600098Y-75689I-984J0D01*
G01*
D13*
X313394Y-195569D02*
G03*
X313394Y-195569I-788J0D01*
G01*
X390356Y-316090D02*
G03*
X390356Y-316090I-788J0D01*
G01*
X275670Y-293818D02*
G03*
X275670Y-293818I-788J0D01*
G01*
X435561Y-216856D02*
G03*
X435561Y-216856I-788J0D01*
G01*
D14*
X224803Y-123228D02*
G03*
X224803Y-123228I-787J0D01*
G01*
X200787Y-122835D02*
G03*
X200787Y-122835I-787J0D01*
G01*
D15*
X-4216Y-192339D02*
G03*
X-4216Y-192339I-1000J0D01*
G01*
X-4216Y-296866D02*
G03*
X-4216Y-296866I-1000J0D01*
G01*
X74548Y-134242D02*
X76911D01*
X74548D02*
Y-131880D01*
X93052Y-134242D02*
X95414D01*
Y-131880D01*
Y-115738D02*
Y-113376D01*
X93052D02*
X95414D01*
X74548D02*
X76911D01*
X74548Y-115738D02*
Y-113376D01*
X60670Y-126663D02*
Y-119774D01*
X54174Y-126663D02*
Y-119774D01*
X61458Y-106289D02*
X61655D01*
X61458Y-109833D02*
X61655D01*
X293032Y-161260D02*
Y-109764D01*
Y-161260D02*
X303031D01*
Y-109764D01*
X293032D02*
X303031D01*
X326555Y-161260D02*
Y-120079D01*
X315965Y-161260D02*
X326555D01*
X315965D02*
Y-120079D01*
X326555D01*
X268898Y-125591D02*
X271654D01*
X268898Y-132283D02*
X271654D01*
X268898Y-144488D02*
X271654D01*
X268898Y-137795D02*
X271654D01*
X268898Y-155905D02*
X271654D01*
X268898Y-149213D02*
X271654D01*
X579109Y-20555D02*
Y-15945D01*
Y-2165D02*
Y555D01*
Y14335D02*
Y18945D01*
X630610D01*
Y-20555D02*
Y18945D01*
X579109Y-20555D02*
X630610D01*
X440846Y-134547D02*
Y-133760D01*
Y-150098D02*
Y-147539D01*
Y-163878D02*
Y-163091D01*
X404823Y-163878D02*
X440846D01*
X404823Y-134547D02*
Y-133760D01*
Y-150098D02*
Y-147539D01*
Y-163878D02*
Y-163091D01*
Y-133760D02*
X440846D01*
X158957Y-97923D02*
X163878D01*
X158996Y-105206D02*
X163917D01*
X77559Y18205D02*
X79921D01*
X82284Y3150D02*
X112205D01*
X82284Y18268D02*
Y21260D01*
Y3150D02*
Y6142D01*
Y21260D02*
X112205D01*
Y18268D02*
Y21260D01*
Y3150D02*
Y6142D01*
X78740Y17024D02*
Y19386D01*
X395374Y-243012D02*
Y-241831D01*
X394193Y-243012D02*
X395374D01*
Y-226673D02*
Y-225492D01*
X394193D02*
X395374D01*
X377854D02*
X379035D01*
X377854Y-226673D02*
Y-225492D01*
Y-243012D02*
Y-240256D01*
Y-243012D02*
X380610D01*
X608858Y-294783D02*
Y-292618D01*
Y-294783D02*
X614764D01*
X625394D02*
X630905D01*
X625394Y-265256D02*
X630905D01*
X608858D02*
X614764D01*
X608858Y-267421D02*
Y-265256D01*
X630905Y-294783D02*
Y-265256D01*
X597441Y-230020D02*
X604134D01*
X597441Y-236122D02*
X604134D01*
X599606Y-189158D02*
X606299D01*
X599606Y-183056D02*
X606299D01*
X597281Y-217062D02*
X622674D01*
Y-193381D02*
Y-190645D01*
Y-217062D02*
Y-214326D01*
X597281Y-190645D02*
X622674D01*
X597281Y-193381D02*
Y-190645D01*
Y-217062D02*
Y-214326D01*
X594280Y-160121D02*
Y-155998D01*
X620680Y-160121D02*
Y-155998D01*
X594280Y-181798D02*
Y-177674D01*
X620680Y-181798D02*
Y-177674D01*
X594280Y-181798D02*
X620680D01*
X594280Y-155998D02*
X620680D01*
X594291Y-153051D02*
X600984D01*
X594291Y-146949D02*
X600984D01*
X476772Y-271752D02*
X483858D01*
X476772Y-259744D02*
X483858D01*
X195768Y-98032D02*
Y-90945D01*
X183760Y-98032D02*
Y-90945D01*
X184055Y-82284D02*
X205118D01*
Y-1476D02*
Y4331D01*
Y-64468D02*
Y-58760D01*
Y-82284D02*
Y-76476D01*
X184055Y4331D02*
X190256D01*
X199508D02*
X205118D01*
X173819Y-63484D02*
Y-57776D01*
X579134Y-282185D02*
Y-261122D01*
X492520D02*
X498327D01*
X555610D02*
X561319D01*
X573327D02*
X579134D01*
X492520Y-282185D02*
Y-275984D01*
Y-266732D02*
Y-261122D01*
X554626Y-292421D02*
X560335D01*
X154367Y-137008D02*
Y-116142D01*
X172083Y-137008D02*
Y-116142D01*
X453937Y-130709D02*
Y-128347D01*
X452756Y-129528D02*
X455118D01*
X444882Y-162992D02*
X447874D01*
X460000D02*
X462992D01*
Y-133071D01*
X444882D02*
X447874D01*
X460000D02*
X462992D01*
X444882Y-162992D02*
Y-133071D01*
X466535Y-116929D02*
Y-87008D01*
X448425Y-116929D02*
X451417D01*
X463543D02*
X466535D01*
X448425D02*
Y-87008D01*
X451417D01*
X463543D02*
X466535D01*
X456299Y-120472D02*
X458661D01*
X457480Y-121653D02*
Y-119291D01*
X351574Y-116983D02*
X358159D01*
X351574Y-122781D02*
X358159D01*
X393410Y-114573D02*
Y-109407D01*
X387898Y-114573D02*
Y-109407D01*
X351574Y-116088D02*
X358159D01*
X351574Y-110290D02*
X358159D01*
X380020Y-115354D02*
Y-108268D01*
X386516Y-115354D02*
Y-108268D01*
X434009Y-197528D02*
Y-196173D01*
X427084Y-200000D02*
X429517D01*
X422591Y-197528D02*
Y-196173D01*
X77953Y12598D02*
X80315D01*
X79134Y11417D02*
Y13780D01*
X45669Y18661D02*
Y21654D01*
Y3543D02*
Y6535D01*
Y3543D02*
X75590D01*
Y18661D02*
Y21654D01*
Y3543D02*
Y6535D01*
X45669Y21654D02*
X75590D01*
X370740Y-150787D02*
Y-138976D01*
X390425D01*
Y-150787D02*
Y-138976D01*
X370740Y-150787D02*
X390425D01*
X393406Y-124114D02*
X394980D01*
X393406Y-117618D02*
X394980D01*
X49567Y-60698D02*
Y-41013D01*
Y-60698D02*
X61378D01*
Y-41013D01*
X49567D02*
X61378D01*
X29140Y-22441D02*
X32277D01*
X29140Y-15354D02*
X32277D01*
X439764Y-118892D02*
Y-115754D01*
X446850Y-118892D02*
Y-115754D01*
X458369Y-121653D02*
X461507D01*
X458369Y-128740D02*
X461507D01*
X366043Y-108268D02*
X371752D01*
X366043Y-115354D02*
X371752D01*
X331693Y-145079D02*
X361221D01*
Y-162795D02*
Y-161319D01*
Y-146555D02*
Y-145079D01*
X331693Y-162795D02*
X361221D01*
X331693D02*
Y-161319D01*
Y-146555D02*
Y-145079D01*
X364862Y-155118D02*
Y-152756D01*
X363681Y-153937D02*
X366043D01*
X331457Y-124803D02*
X361378D01*
Y-142913D02*
Y-139921D01*
Y-127795D02*
Y-124803D01*
X331457Y-142913D02*
X361378D01*
X331457D02*
Y-139921D01*
Y-127795D02*
Y-124803D01*
X364921Y-135039D02*
Y-132677D01*
X363740Y-133858D02*
X366102D01*
X43406Y-31594D02*
Y-30807D01*
Y-17815D02*
Y-15256D01*
Y-2264D02*
Y-1476D01*
X79429D01*
Y-31594D02*
Y-30807D01*
Y-17815D02*
Y-15256D01*
Y-2264D02*
Y-1476D01*
X43406Y-31594D02*
X79429D01*
X81496Y-36909D02*
X83071D01*
X81496Y-43406D02*
X83071D01*
X75984Y-77165D02*
X78347D01*
X77165Y-78347D02*
Y-75984D01*
X110630Y-86221D02*
Y-83228D01*
Y-71102D02*
Y-68110D01*
X80709D02*
X110630D01*
X80709Y-86221D02*
Y-83228D01*
Y-71102D02*
Y-68110D01*
Y-86221D02*
X110630D01*
X94685Y-64764D02*
Y-35236D01*
X110925D02*
X112402D01*
X94685D02*
X96161D01*
X112402Y-64764D02*
Y-35236D01*
X110925Y-64764D02*
X112402D01*
X94685D02*
X96161D01*
X102362Y-31594D02*
X104724D01*
X103543Y-32776D02*
Y-30413D01*
X78257Y-58179D02*
X83966D01*
X78257Y-65266D02*
X83966D01*
X451181Y-79429D02*
X457874D01*
X451181Y-73327D02*
X457874D01*
X91929Y-89075D02*
X98622D01*
X91929Y-95177D02*
X98622D01*
X91983Y-102505D02*
X98568D01*
X91983Y-96708D02*
X98568D01*
X466393Y-73479D02*
X472977D01*
X466393Y-79277D02*
X472977D01*
X29140Y-13386D02*
X32277D01*
X29140Y-6299D02*
X32277D01*
X597441Y-217421D02*
X604134D01*
X597441Y-223524D02*
X604134D01*
X275886Y-198819D02*
Y-191732D01*
X287894Y-198819D02*
Y-191732D01*
X240551Y-126378D02*
Y-119291D01*
X220866Y-126378D02*
Y-119291D01*
X240551D01*
X220866Y-126378D02*
X240551D01*
X216535Y-125984D02*
Y-118110D01*
X196850Y-125984D02*
Y-118110D01*
X216535D01*
X196850Y-125984D02*
X216535D01*
X179367Y-124705D02*
Y-122146D01*
X185666Y-124705D02*
Y-122146D01*
X165212Y-105261D02*
Y-98676D01*
X171009Y-105261D02*
Y-98676D01*
X426618Y-360163D02*
Y-358391D01*
X422681Y-360163D02*
X426618D01*
Y-353273D02*
Y-351502D01*
X422681D02*
X426618D01*
X471402Y-360950D02*
Y-359179D01*
X467465Y-360950D02*
X471402D01*
Y-354061D02*
Y-352289D01*
X467465D02*
X471402D01*
X509823Y-360627D02*
Y-358855D01*
X505886Y-360627D02*
X509823D01*
Y-353737D02*
Y-351966D01*
X505886D02*
X509823D01*
X554803Y-360430D02*
Y-358659D01*
X550866Y-360430D02*
X554803D01*
Y-353540D02*
Y-351769D01*
X550866D02*
X554803D01*
X597441Y-223721D02*
X604134D01*
X597441Y-229823D02*
X604134D01*
X25095Y-212795D02*
Y-208465D01*
X7260Y-240551D02*
X12426D01*
X7260Y-235039D02*
X12426D01*
X4504Y-351969D02*
X9669D01*
X4504Y-346457D02*
X9669D01*
X16929Y-301008D02*
Y-295842D01*
X11417Y-301008D02*
Y-295842D01*
X9228Y-196063D02*
X14394D01*
X9228Y-190551D02*
X14394D01*
X-7677Y-190945D02*
X5610D01*
X-7677D02*
Y-174803D01*
X5709Y-190945D02*
Y-174803D01*
X-7677D02*
X5709D01*
X322047Y-245768D02*
X329134D01*
X322047Y-233760D02*
X329134D01*
X602303Y-309232D02*
Y-308307D01*
X622303Y-309232D02*
Y-308307D01*
X602303D02*
X622303D01*
X602303Y-358307D02*
X622303D01*
Y-357382D01*
X602303Y-358307D02*
Y-357382D01*
X25394Y-5020D02*
X32087D01*
X25394Y1083D02*
X32087D01*
X25394Y1870D02*
X32087D01*
X25394Y7972D02*
X32087D01*
X25394Y8760D02*
X32087D01*
X25394Y14862D02*
X32087D01*
X25394Y15650D02*
X32087D01*
X25394Y21752D02*
X32087D01*
X145177Y-105123D02*
Y-98036D01*
X151673Y-105123D02*
Y-98036D01*
X156048Y-104867D02*
Y-98282D01*
X150251Y-104867D02*
Y-98282D01*
X608547Y-259197D02*
X612681D01*
X608563Y-254134D02*
X612697D01*
X621654Y-246911D02*
Y-235100D01*
X608858Y-246911D02*
Y-235100D01*
X596736Y-296342D02*
X607989D01*
X596736Y-303658D02*
X607989D01*
X611984Y-300000D02*
X617150D01*
X611984Y-305512D02*
X617150D01*
X595986Y-289446D02*
X600119D01*
X595965Y-294783D02*
X600098D01*
X608584Y-258344D02*
X612718D01*
X608563Y-263681D02*
X612697D01*
X335827Y-298917D02*
X342913D01*
X335827Y-286910D02*
X342913D01*
X316929Y-299705D02*
X324016D01*
X316929Y-287697D02*
X324016D01*
X577776Y-76811D02*
Y-72539D01*
Y-56595D02*
Y-52323D01*
X549784D02*
X577776D01*
X549784Y-76811D02*
Y-72539D01*
Y-56595D02*
Y-52323D01*
Y-76811D02*
X577776D01*
X596063Y-78740D02*
X615748D01*
Y-66929D01*
X596063D02*
X615748D01*
X596063Y-78740D02*
Y-66929D01*
X594193Y-49114D02*
X595768D01*
X594193Y-55610D02*
X595768D01*
X602559Y-35630D02*
Y-32874D01*
X595866Y-35630D02*
Y-32874D01*
X-13898Y-330561D02*
X-3032D01*
X-22244Y-322214D02*
Y-311348D01*
X5315Y-322214D02*
Y-311348D01*
X-13898Y-303002D02*
X-3032D01*
X-13898Y-277410D02*
X-3032D01*
X-22244Y-269063D02*
Y-258197D01*
X5315Y-269063D02*
Y-258197D01*
X-13898Y-249850D02*
X-3032D01*
X-13898Y-224260D02*
X-3032D01*
X-22244Y-215913D02*
Y-205047D01*
X5315Y-215913D02*
Y-205047D01*
X-13898Y-196701D02*
X-3032D01*
X-13898Y-171112D02*
X-3032D01*
X-22244Y-162765D02*
Y-151899D01*
X5315Y-162765D02*
Y-151899D01*
X-13898Y-143553D02*
X-3032D01*
X17717Y-235827D02*
X24016D01*
X17717D02*
Y-227953D01*
X24016D01*
Y-235827D02*
Y-227953D01*
X25394Y-236811D02*
X28740D01*
X17717Y-188189D02*
X24016D01*
X17717D02*
Y-180315D01*
X24016D01*
Y-188189D02*
Y-180315D01*
X25394Y-189173D02*
X28740D01*
X17717Y-292913D02*
X24016D01*
X17717D02*
Y-285039D01*
X24016D01*
Y-292913D02*
Y-285039D01*
X25394Y-293898D02*
X28740D01*
X25095Y-264961D02*
Y-260630D01*
X25095Y-159498D02*
Y-155167D01*
X12598Y-345669D02*
X18898D01*
X12598D02*
Y-337795D01*
X18898D01*
Y-345669D02*
Y-337795D01*
X20276Y-346654D02*
X23622D01*
X25095Y-319094D02*
Y-314764D01*
X624449Y-153189D02*
Y-93189D01*
X604449D02*
X624449D01*
X604449Y-153189D02*
Y-93189D01*
Y-153189D02*
X624449D01*
X-7677Y-279331D02*
X5709D01*
Y-295472D02*
Y-279331D01*
X-7677Y-295472D02*
Y-279331D01*
Y-295472D02*
X5610D01*
X137922Y-133468D02*
Y-123232D01*
X125717Y-133468D02*
Y-123232D01*
D16*
X-24400Y-335681D02*
G03*
X-24400Y-346705I4106J-5512D01*
G01*
Y-282925D02*
G03*
X-24400Y-293949I4106J-5512D01*
G01*
Y-229776D02*
G03*
X-24400Y-240799I4106J-5512D01*
G01*
Y-60091D02*
G03*
X-24400Y-71114I4106J-5512D01*
G01*
Y-103004D02*
G03*
X-24400Y-114028I4106J-5512D01*
G01*
X-24803Y-177165D02*
G03*
X-24803Y-188189I4106J-5512D01*
G01*
X463018Y-344132D02*
Y-166966D01*
X246482Y-344132D02*
X463018D01*
X246482Y-166966D02*
X463018D01*
X246482Y-344132D02*
Y-166966D01*
D17*
X-18406Y-190157D02*
G03*
X-18799Y-190157I-197J0D01*
G01*
D02*
G03*
X-18406Y-190157I197J0D01*
G01*
X-18502Y-73032D02*
G03*
X-18702Y-73032I-100J0D01*
G01*
D02*
G03*
X-18502Y-73032I100J0D01*
G01*
X-18799Y-242913D02*
G03*
X-18406Y-242913I197J0D01*
G01*
D02*
G03*
X-18799Y-242913I-197J0D01*
G01*
Y-296457D02*
G03*
X-18406Y-296457I197J0D01*
G01*
D02*
G03*
X-18799Y-296457I-197J0D01*
G01*
Y-349213D02*
G03*
X-18406Y-349213I197J0D01*
G01*
D02*
G03*
X-18799Y-349213I-197J0D01*
G01*
X-18802Y-116339D02*
G03*
X-18402Y-116339I200J0D01*
G01*
D02*
G03*
X-18802Y-116339I-200J0D01*
G01*
X581496Y-166535D02*
X583975Y-164057D01*
Y-163896D01*
X581102Y-161024D02*
X583976Y-163898D01*
X584196D01*
X570079Y-163779D02*
X584196Y-163898D01*
X581102Y-176378D02*
X583651Y-173898D01*
X581102Y-171260D02*
X583651Y-173898D01*
X575197D02*
X583651D01*
X575197Y-194095D02*
Y-173898D01*
X558661Y-194095D02*
X575197D01*
X588189Y-213386D02*
X590190Y-211385D01*
Y-211353D01*
X588399Y-209732D02*
X590021Y-211353D01*
X590190D01*
X584252Y-197638D02*
X587402Y-201118D01*
X584252Y-203937D02*
X587402Y-201118D01*
X587795Y-207874D02*
X589764Y-205906D01*
Y-205906D01*
X587795Y-203937D02*
X589764Y-205906D01*
X586614D02*
X589764D01*
X553937Y-201118D02*
X587402D01*
X553937Y-217717D02*
Y-201181D01*
X522047Y-217717D02*
X553937D01*
X559449Y-205906D02*
X586614D01*
X559449Y-225197D02*
Y-205906D01*
X511417Y-225197D02*
X559449D01*
X568110Y-211353D02*
X590190D01*
X568110Y-234646D02*
Y-211353D01*
X490459Y-234711D02*
X568110Y-234646D01*
D18*
X204102Y-234680D02*
G03*
X204102Y-234680I-500J0D01*
G01*
D02*
G03*
X204102Y-234680I-500J0D01*
G01*
X579134Y-260633D02*
Y-95279D01*
X492520Y-260633D02*
Y-95279D01*
X579134D01*
X492520Y-260633D02*
X579134D01*
X205607Y-82284D02*
X370961D01*
X205607Y4331D02*
X370961D01*
Y-82284D02*
Y4331D01*
X205607Y-82284D02*
Y4331D01*
X205607Y-98032D02*
X441828D01*
X205607Y20079D02*
X441828D01*
Y-98032D02*
Y20079D01*
X205607Y-98032D02*
Y20079D01*
X114242Y19124D02*
X378730D01*
Y-105876D02*
Y19124D01*
X114242Y-105876D02*
X378730D01*
X114242D02*
Y19124D01*
X468376Y-344222D02*
X593376D01*
Y-79734D01*
X468376D02*
X593376D01*
X468376Y-344222D02*
Y-79734D01*
X38189Y-343701D02*
Y-143701D01*
X238189D01*
Y-343701D02*
Y-143701D01*
X38189Y-343701D02*
X238189D01*
X480253Y-223772D02*
Y-225772D01*
X481752D01*
Y-224772D01*
Y-225772D01*
X483252D01*
Y-222773D02*
X480253D01*
Y-221273D01*
X480753Y-220773D01*
X481752D01*
X482252Y-221273D01*
Y-222773D01*
X480753Y-217774D02*
X480253Y-218274D01*
Y-219274D01*
X480753Y-219774D01*
X482752D01*
X483252Y-219274D01*
Y-218274D01*
X482752Y-217774D01*
X481752D01*
Y-218774D01*
X483252Y-216775D02*
X481253D01*
X480253Y-215775D01*
X481253Y-214775D01*
X483252D01*
X481752D01*
Y-216775D01*
X483252Y-209277D02*
X481752Y-210776D01*
X480253Y-209277D01*
X481752Y-207778D02*
Y-205778D01*
X483252Y-204778D02*
X481752Y-203279D01*
X480253Y-204778D01*
X480753Y-197281D02*
X480253Y-197781D01*
Y-198780D01*
X480753Y-199280D01*
X482752D01*
X483252Y-198780D01*
Y-197781D01*
X482752Y-197281D01*
X481752D01*
Y-198281D01*
X483252Y-196281D02*
X480253D01*
Y-194782D01*
X480753Y-194282D01*
X481752D01*
X482252Y-194782D01*
Y-196281D01*
X480753Y-191283D02*
X480253Y-191783D01*
Y-192782D01*
X480753Y-193282D01*
X481253D01*
X481752Y-192782D01*
Y-191783D01*
X482252Y-191283D01*
X482752D01*
X483252Y-191783D01*
Y-192782D01*
X482752Y-193282D01*
X483252Y-188284D02*
Y-190283D01*
X481253Y-188284D01*
X480753D01*
X480253Y-188784D01*
Y-189783D01*
X480753Y-190283D01*
X483252Y-183285D02*
X482252Y-184285D01*
X481253D01*
X480253Y-183285D01*
X483252Y-181786D02*
X480253D01*
X483252Y-179787D01*
X480253D01*
X483252Y-178287D02*
Y-177287D01*
X482752Y-176787D01*
X481752D01*
X481253Y-177287D01*
Y-178287D01*
X481752Y-178787D01*
X482752D01*
X483252Y-178287D01*
X481253Y-175788D02*
X483252D01*
X482252D01*
X481752Y-175288D01*
X481253Y-174788D01*
Y-174288D01*
X483252Y-172789D02*
X481253D01*
Y-172289D01*
X481752Y-171789D01*
X483252D01*
X481752D01*
X481253Y-171289D01*
X481752Y-170790D01*
X483252D01*
X481253Y-169290D02*
Y-168290D01*
X481752Y-167790D01*
X483252D01*
Y-169290D01*
X482752Y-169790D01*
X482252Y-169290D01*
Y-167790D01*
X483252Y-166791D02*
Y-165791D01*
Y-166291D01*
X480253D01*
Y-166791D01*
X483252Y-164292D02*
X482252Y-163292D01*
X481253D01*
X480253Y-164292D01*
X552810Y-196856D02*
X555809D01*
Y-194857D01*
X552810Y-191858D02*
Y-193857D01*
X555809D01*
Y-191858D01*
X554310Y-193857D02*
Y-192857D01*
X552810Y-190858D02*
X555809D01*
Y-189359D01*
X555309Y-188859D01*
X553310D01*
X552810Y-189359D01*
Y-190858D01*
X555809Y-183860D02*
X554810Y-184860D01*
X553810D01*
X552810Y-183860D01*
Y-182361D02*
X555809D01*
Y-180861D01*
X555309Y-180361D01*
X553310D01*
X552810Y-180861D01*
Y-182361D01*
X555809Y-179362D02*
Y-178362D01*
Y-178862D01*
X552810D01*
X553310Y-179362D01*
X555809Y-174863D02*
Y-176863D01*
X553810Y-174863D01*
X553310D01*
X552810Y-175363D01*
Y-176363D01*
X553310Y-176863D01*
X555809Y-173864D02*
X554810Y-172864D01*
X553810D01*
X552810Y-173864D01*
Y-166866D02*
Y-167866D01*
X553310Y-168365D01*
X555309D01*
X555809Y-167866D01*
Y-166866D01*
X555309Y-166366D01*
X553310D01*
X552810Y-166866D01*
X555809Y-165366D02*
X553810D01*
Y-163867D01*
X554310Y-163367D01*
X555809D01*
Y-158869D02*
X553310D01*
X554310D01*
Y-159368D01*
Y-158369D01*
Y-158869D01*
X553310D01*
X552810Y-158369D01*
X555809Y-156369D02*
Y-155370D01*
X555309Y-154870D01*
X554310D01*
X553810Y-155370D01*
Y-156369D01*
X554310Y-156869D01*
X555309D01*
X555809Y-156369D01*
X553810Y-153870D02*
X555809D01*
X554810D01*
X554310Y-153370D01*
X553810Y-152870D01*
Y-152371D01*
X555809Y-147872D02*
X552810D01*
Y-146372D01*
X553310Y-145873D01*
X554310D01*
X554810Y-146372D01*
Y-147872D01*
Y-146872D02*
X555809Y-145873D01*
X553310Y-142874D02*
X552810Y-143374D01*
Y-144373D01*
X553310Y-144873D01*
X555309D01*
X555809Y-144373D01*
Y-143374D01*
X555309Y-142874D01*
X552810Y-141874D02*
X555809D01*
Y-140374D01*
X555309Y-139875D01*
X554810D01*
X554310Y-140374D01*
Y-141874D01*
Y-140374D01*
X553810Y-139875D01*
X553310D01*
X552810Y-140374D01*
Y-141874D01*
X556309Y-138375D02*
X555809Y-137875D01*
X555309D01*
Y-138375D01*
X555809D01*
Y-137875D01*
X556309Y-138375D01*
X556809Y-138875D01*
X552810Y-131377D02*
Y-132377D01*
X553310Y-132877D01*
X555309D01*
X555809Y-132377D01*
Y-131377D01*
X555309Y-130877D01*
X553310D01*
X552810Y-131377D01*
X555809Y-129378D02*
X553310D01*
X554310D01*
Y-129878D01*
Y-128878D01*
Y-129378D01*
X553310D01*
X552810Y-128878D01*
X555809Y-126879D02*
X553310D01*
X554310D01*
Y-127379D01*
Y-126379D01*
Y-126879D01*
X553310D01*
X552810Y-126379D01*
X555809Y-121381D02*
X553310D01*
X554310D01*
Y-121880D01*
Y-120881D01*
Y-121381D01*
X553310D01*
X552810Y-120881D01*
X555809Y-118881D02*
Y-117882D01*
X555309Y-117382D01*
X554310D01*
X553810Y-117882D01*
Y-118881D01*
X554310Y-119381D01*
X555309D01*
X555809Y-118881D01*
X553810Y-116382D02*
X555809D01*
X554810D01*
X554310Y-115882D01*
X553810Y-115383D01*
Y-114883D01*
X555809Y-110384D02*
X552810D01*
X553810Y-109385D01*
X552810Y-108385D01*
X555809D01*
Y-105386D02*
Y-107385D01*
X553810Y-105386D01*
X553310D01*
X552810Y-105886D01*
Y-106885D01*
X553310Y-107385D01*
X563112Y-189101D02*
X566111D01*
Y-187102D01*
X563112Y-184103D02*
Y-186102D01*
X566111D01*
Y-184103D01*
X564611Y-186102D02*
Y-185102D01*
X563112Y-183103D02*
X566111D01*
Y-181604D01*
X565611Y-181104D01*
X563612D01*
X563112Y-181604D01*
Y-183103D01*
X566111Y-176105D02*
X565111Y-177105D01*
X564111D01*
X563112Y-176105D01*
Y-174606D02*
X566111D01*
Y-173106D01*
X565611Y-172606D01*
X563612D01*
X563112Y-173106D01*
Y-174606D01*
X566111Y-171607D02*
Y-170607D01*
Y-171107D01*
X563112D01*
X563612Y-171607D01*
X565611Y-169107D02*
X566111Y-168608D01*
Y-167608D01*
X565611Y-167108D01*
X563612D01*
X563112Y-167608D01*
Y-168608D01*
X563612Y-169107D01*
X564111D01*
X564611Y-168608D01*
Y-167108D01*
X566111Y-166109D02*
X565111Y-165109D01*
X564111D01*
X563112Y-166109D01*
Y-159111D02*
Y-160110D01*
X563612Y-160610D01*
X565611D01*
X566111Y-160110D01*
Y-159111D01*
X565611Y-158611D01*
X563612D01*
X563112Y-159111D01*
X566111Y-157611D02*
X564111D01*
Y-156112D01*
X564611Y-155612D01*
X566111D01*
Y-151113D02*
X563612D01*
X564611D01*
Y-151613D01*
Y-150613D01*
Y-151113D01*
X563612D01*
X563112Y-150613D01*
X566111Y-148614D02*
Y-147615D01*
X565611Y-147115D01*
X564611D01*
X564111Y-147615D01*
Y-148614D01*
X564611Y-149114D01*
X565611D01*
X566111Y-148614D01*
X564111Y-146115D02*
X566111D01*
X565111D01*
X564611Y-145615D01*
X564111Y-145115D01*
Y-144615D01*
X566111Y-140117D02*
X563112D01*
Y-138617D01*
X563612Y-138118D01*
X564611D01*
X565111Y-138617D01*
Y-140117D01*
Y-139117D02*
X566111Y-138118D01*
X563612Y-135118D02*
X563112Y-135618D01*
Y-136618D01*
X563612Y-137118D01*
X565611D01*
X566111Y-136618D01*
Y-135618D01*
X565611Y-135118D01*
X563112Y-134119D02*
X566111D01*
Y-132619D01*
X565611Y-132120D01*
X565111D01*
X564611Y-132619D01*
Y-134119D01*
Y-132619D01*
X564111Y-132120D01*
X563612D01*
X563112Y-132619D01*
Y-134119D01*
X566610Y-130620D02*
X566111Y-130120D01*
X565611D01*
Y-130620D01*
X566111D01*
Y-130120D01*
X566610Y-130620D01*
X567110Y-131120D01*
X563112Y-123622D02*
Y-124622D01*
X563612Y-125122D01*
X565611D01*
X566111Y-124622D01*
Y-123622D01*
X565611Y-123122D01*
X563612D01*
X563112Y-123622D01*
X566111Y-121623D02*
X563612D01*
X564611D01*
Y-122123D01*
Y-121123D01*
Y-121623D01*
X563612D01*
X563112Y-121123D01*
X566111Y-119124D02*
X563612D01*
X564611D01*
Y-119623D01*
Y-118624D01*
Y-119124D01*
X563612D01*
X563112Y-118624D01*
X566111Y-113626D02*
X563612D01*
X564611D01*
Y-114125D01*
Y-113126D01*
Y-113626D01*
X563612D01*
X563112Y-113126D01*
X566111Y-111126D02*
Y-110127D01*
X565611Y-109627D01*
X564611D01*
X564111Y-110127D01*
Y-111126D01*
X564611Y-111626D01*
X565611D01*
X566111Y-111126D01*
X564111Y-108627D02*
X566111D01*
X565111D01*
X564611Y-108127D01*
X564111Y-107627D01*
Y-107128D01*
X566111Y-102629D02*
X563112D01*
X564111Y-101629D01*
X563112Y-100630D01*
X566111D01*
Y-97631D02*
Y-99630D01*
X564111Y-97631D01*
X563612D01*
X563112Y-98131D01*
Y-99130D01*
X563612Y-99630D01*
X516968Y-220476D02*
X519967D01*
Y-218477D01*
X516968Y-215478D02*
Y-217477D01*
X519967D01*
Y-215478D01*
X518467Y-217477D02*
Y-216478D01*
X516968Y-214478D02*
X519967D01*
Y-212979D01*
X519467Y-212479D01*
X517467D01*
X516968Y-212979D01*
Y-214478D01*
X519967Y-207481D02*
X518967Y-208480D01*
X517967D01*
X516968Y-207481D01*
Y-205981D02*
X519967D01*
Y-204482D01*
X519467Y-203982D01*
X517467D01*
X516968Y-204482D01*
Y-205981D01*
X519967Y-200983D02*
Y-202982D01*
X517967Y-200983D01*
X517467D01*
X516968Y-201483D01*
Y-202482D01*
X517467Y-202982D01*
X519967Y-198483D02*
X516968D01*
X518467Y-199983D01*
Y-197984D01*
X519967Y-196984D02*
X518967Y-195984D01*
X517967D01*
X516968Y-196984D01*
Y-189986D02*
Y-190986D01*
X517467Y-191486D01*
X519467D01*
X519967Y-190986D01*
Y-189986D01*
X519467Y-189486D01*
X517467D01*
X516968Y-189986D01*
X519967Y-188487D02*
X517967D01*
Y-186987D01*
X518467Y-186487D01*
X519967D01*
Y-181989D02*
X517467D01*
X518467D01*
Y-182489D01*
Y-181489D01*
Y-181989D01*
X517467D01*
X516968Y-181489D01*
X519967Y-179490D02*
Y-178490D01*
X519467Y-177990D01*
X518467D01*
X517967Y-178490D01*
Y-179490D01*
X518467Y-179989D01*
X519467D01*
X519967Y-179490D01*
X517967Y-176990D02*
X519967D01*
X518967D01*
X518467Y-176491D01*
X517967Y-175991D01*
Y-175491D01*
X516968Y-170992D02*
Y-169993D01*
Y-170492D01*
X519967D01*
Y-170992D01*
Y-169993D01*
Y-166494D02*
Y-168493D01*
X517967Y-166494D01*
X517467D01*
X516968Y-166994D01*
Y-167993D01*
X517467Y-168493D01*
Y-163495D02*
X516968Y-163995D01*
Y-164994D01*
X517467Y-165494D01*
X519467D01*
X519967Y-164994D01*
Y-163995D01*
X519467Y-163495D01*
X520467Y-161995D02*
X519967Y-161495D01*
X519467D01*
Y-161995D01*
X519967D01*
Y-161495D01*
X520467Y-161995D01*
X520966Y-162495D01*
X516968Y-154998D02*
Y-155997D01*
X517467Y-156497D01*
X519467D01*
X519967Y-155997D01*
Y-154998D01*
X519467Y-154498D01*
X517467D01*
X516968Y-154998D01*
X519967Y-152998D02*
X517467D01*
X518467D01*
Y-153498D01*
Y-152498D01*
Y-152998D01*
X517467D01*
X516968Y-152498D01*
X519967Y-150499D02*
X517467D01*
X518467D01*
Y-150999D01*
Y-149999D01*
Y-150499D01*
X517467D01*
X516968Y-149999D01*
X519967Y-145001D02*
X517467D01*
X518467D01*
Y-145501D01*
Y-144501D01*
Y-145001D01*
X517467D01*
X516968Y-144501D01*
X519967Y-142501D02*
Y-141502D01*
X519467Y-141002D01*
X518467D01*
X517967Y-141502D01*
Y-142501D01*
X518467Y-143001D01*
X519467D01*
X519967Y-142501D01*
X517967Y-140002D02*
X519967D01*
X518967D01*
X518467Y-139503D01*
X517967Y-139003D01*
Y-138503D01*
X516968Y-134004D02*
X519467D01*
X519967Y-133504D01*
Y-132505D01*
X519467Y-132005D01*
X516968D01*
X519967Y-131005D02*
X517967D01*
X516968Y-130006D01*
X517967Y-129006D01*
X519967D01*
X518467D01*
Y-131005D01*
X519967Y-128006D02*
X516968D01*
Y-126507D01*
X517467Y-126007D01*
X518467D01*
X518967Y-126507D01*
Y-128006D01*
Y-127007D02*
X519967Y-126007D01*
X516968Y-125007D02*
Y-123008D01*
Y-124007D01*
X519967D01*
X485553Y-237976D02*
X488552D01*
Y-235977D01*
X485553Y-232978D02*
Y-234977D01*
X488552D01*
Y-232978D01*
X487052Y-234977D02*
Y-233978D01*
X485553Y-231978D02*
X488552D01*
Y-230479D01*
X488052Y-229979D01*
X486052D01*
X485553Y-230479D01*
Y-231978D01*
X488552Y-224981D02*
X487552Y-225980D01*
X486552D01*
X485553Y-224981D01*
Y-223481D02*
X488552D01*
Y-221982D01*
X488052Y-221482D01*
X486052D01*
X485553Y-221982D01*
Y-223481D01*
X488552Y-218483D02*
Y-220482D01*
X486552Y-218483D01*
X486052D01*
X485553Y-218983D01*
Y-219982D01*
X486052Y-220482D01*
X488552Y-217483D02*
Y-216483D01*
Y-216983D01*
X485553D01*
X486052Y-217483D01*
X488552Y-214984D02*
X487552Y-213984D01*
X486552D01*
X485553Y-214984D01*
Y-209486D02*
X488552D01*
Y-207486D01*
Y-206487D02*
Y-205487D01*
Y-205987D01*
X486552D01*
Y-206487D01*
X486052Y-203487D02*
X486552D01*
Y-203987D01*
Y-202988D01*
Y-203487D01*
X488052D01*
X488552Y-202988D01*
Y-197989D02*
X486052D01*
X487052D01*
Y-198489D01*
Y-197490D01*
Y-197989D01*
X486052D01*
X485553Y-197490D01*
X488552Y-195490D02*
Y-194491D01*
X488052Y-193991D01*
X487052D01*
X486552Y-194491D01*
Y-195490D01*
X487052Y-195990D01*
X488052D01*
X488552Y-195490D01*
X486552Y-192991D02*
X488552D01*
X487552D01*
X487052Y-192491D01*
X486552Y-191991D01*
Y-191491D01*
X485553Y-186993D02*
X488052D01*
X488552Y-186493D01*
Y-185493D01*
X488052Y-184994D01*
X485553D01*
X486052Y-181994D02*
X485553Y-182494D01*
Y-183494D01*
X486052Y-183994D01*
X486552D01*
X487052Y-183494D01*
Y-182494D01*
X487552Y-181994D01*
X488052D01*
X488552Y-182494D01*
Y-183494D01*
X488052Y-183994D01*
X485553Y-180995D02*
X488552D01*
Y-179495D01*
X488052Y-178996D01*
X487552D01*
X487052Y-179495D01*
Y-180995D01*
Y-179495D01*
X486552Y-178996D01*
X486052D01*
X485553Y-179495D01*
Y-180995D01*
Y-172997D02*
Y-174997D01*
X487052D01*
Y-173997D01*
Y-174997D01*
X488552D01*
X485553Y-171998D02*
Y-169998D01*
Y-170998D01*
X488552D01*
X485553Y-168999D02*
X488552D01*
Y-167499D01*
X488052Y-166999D01*
X486052D01*
X485553Y-167499D01*
Y-168999D01*
Y-166000D02*
Y-165000D01*
Y-165500D01*
X488552D01*
Y-166000D01*
Y-165000D01*
Y-159002D02*
X487052Y-160501D01*
X485553Y-159002D01*
X487052Y-157502D02*
Y-155503D01*
X488552Y-154503D02*
X487052Y-153004D01*
X485553Y-154503D01*
X486052Y-147006D02*
X485553Y-147506D01*
Y-148505D01*
X486052Y-149005D01*
X488052D01*
X488552Y-148505D01*
Y-147506D01*
X488052Y-147006D01*
X487052D01*
Y-148005D01*
X488552Y-146006D02*
X485553D01*
Y-144507D01*
X486052Y-144007D01*
X487052D01*
X487552Y-144507D01*
Y-146006D01*
X486052Y-141008D02*
X485553Y-141508D01*
Y-142507D01*
X486052Y-143007D01*
X486552D01*
X487052Y-142507D01*
Y-141508D01*
X487552Y-141008D01*
X488052D01*
X488552Y-141508D01*
Y-142507D01*
X488052Y-143007D01*
X488552Y-138009D02*
Y-140008D01*
X486552Y-138009D01*
X486052D01*
X485553Y-138509D01*
Y-139508D01*
X486052Y-140008D01*
X488552Y-133010D02*
X487552Y-134010D01*
X486552D01*
X485553Y-133010D01*
Y-131511D02*
X488552D01*
Y-130011D01*
X488052Y-129511D01*
X486052D01*
X485553Y-130011D01*
Y-131511D01*
X488552Y-127012D02*
Y-128012D01*
X488052Y-128512D01*
X487052D01*
X486552Y-128012D01*
Y-127012D01*
X487052Y-126512D01*
X487552D01*
Y-128512D01*
X485553Y-125513D02*
X488552D01*
Y-124013D01*
X488052Y-123513D01*
X487552D01*
X487052D01*
X486552Y-124013D01*
Y-125513D01*
Y-122514D02*
X488052D01*
X488552Y-122014D01*
Y-120514D01*
X486552D01*
X489551Y-118515D02*
Y-118015D01*
X489051Y-117515D01*
X486552D01*
Y-119015D01*
X487052Y-119515D01*
X488052D01*
X488552Y-119015D01*
Y-117515D01*
Y-116516D02*
X486552Y-114516D01*
X488552Y-113517D02*
X485553D01*
Y-112017D01*
X486052Y-111517D01*
X487052D01*
X487552Y-112017D01*
Y-113517D01*
X486552Y-110518D02*
X488552D01*
X487552D01*
X487052Y-110018D01*
X486552Y-109518D01*
Y-109018D01*
X488552Y-107019D02*
Y-106019D01*
X488052Y-105519D01*
X487052D01*
X486552Y-106019D01*
Y-107019D01*
X487052Y-107519D01*
X488052D01*
X488552Y-107019D01*
X489551Y-103520D02*
Y-103020D01*
X489051Y-102520D01*
X486552D01*
Y-104020D01*
X487052Y-104520D01*
X488052D01*
X488552Y-104020D01*
Y-102520D01*
Y-101521D02*
X487552Y-100521D01*
X486552D01*
X485553Y-101521D01*
X475135Y-237976D02*
X478134D01*
Y-235977D01*
X475135Y-232978D02*
Y-234977D01*
X478134D01*
Y-232978D01*
X476634Y-234977D02*
Y-233978D01*
X475135Y-231978D02*
X478134D01*
Y-230479D01*
X477634Y-229979D01*
X475635D01*
X475135Y-230479D01*
Y-231978D01*
X478134Y-224981D02*
X477134Y-225980D01*
X476134D01*
X475135Y-224981D01*
Y-223481D02*
X478134D01*
Y-221982D01*
X477634Y-221482D01*
X475635D01*
X475135Y-221982D01*
Y-223481D01*
X478134Y-218483D02*
Y-220482D01*
X476134Y-218483D01*
X475635D01*
X475135Y-218983D01*
Y-219982D01*
X475635Y-220482D01*
X478134Y-217483D02*
Y-216483D01*
Y-216983D01*
X475135D01*
X475635Y-217483D01*
X478134Y-214984D02*
X477134Y-213984D01*
X476134D01*
X475135Y-214984D01*
Y-207986D02*
Y-208986D01*
X475635Y-209486D01*
X477634D01*
X478134Y-208986D01*
Y-207986D01*
X477634Y-207486D01*
X475635D01*
X475135Y-207986D01*
X478134Y-205987D02*
X475635D01*
X476634D01*
Y-206487D01*
Y-205487D01*
Y-205987D01*
X475635D01*
X475135Y-205487D01*
X478134Y-203487D02*
X475635D01*
X476634D01*
Y-203987D01*
Y-202988D01*
Y-203487D01*
X475635D01*
X475135Y-202988D01*
X478134Y-197989D02*
X475635D01*
X476634D01*
Y-198489D01*
Y-197490D01*
Y-197989D01*
X475635D01*
X475135Y-197490D01*
X478134Y-195490D02*
Y-194490D01*
X477634Y-193991D01*
X476634D01*
X476134Y-194490D01*
Y-195490D01*
X476634Y-195990D01*
X477634D01*
X478134Y-195490D01*
X476134Y-192991D02*
X478134D01*
X477134D01*
X476634Y-192491D01*
X476134Y-191991D01*
Y-191491D01*
X475135Y-186993D02*
X477634D01*
X478134Y-186493D01*
Y-185493D01*
X477634Y-184994D01*
X475135D01*
X475635Y-181994D02*
X475135Y-182494D01*
Y-183494D01*
X475635Y-183994D01*
X476134D01*
X476634Y-183494D01*
Y-182494D01*
X477134Y-181994D01*
X477634D01*
X478134Y-182494D01*
Y-183494D01*
X477634Y-183994D01*
X475135Y-180995D02*
X478134D01*
Y-179495D01*
X477634Y-178996D01*
X477134D01*
X476634Y-179495D01*
Y-180995D01*
Y-179495D01*
X476134Y-178996D01*
X475635D01*
X475135Y-179495D01*
Y-180995D01*
Y-172997D02*
Y-174997D01*
X476634D01*
Y-173997D01*
Y-174997D01*
X478134D01*
X475135Y-171998D02*
Y-169998D01*
Y-170998D01*
X478134D01*
X475135Y-168999D02*
X478134D01*
Y-167499D01*
X477634Y-166999D01*
X475635D01*
X475135Y-167499D01*
Y-168999D01*
Y-166000D02*
Y-165000D01*
Y-165500D01*
X478134D01*
Y-166000D01*
Y-165000D01*
Y-159002D02*
X476634Y-160501D01*
X475135Y-159002D01*
X476634Y-157502D02*
Y-155503D01*
X478134Y-154503D02*
X476634Y-153004D01*
X475135Y-154503D01*
Y-147006D02*
Y-149005D01*
X476634D01*
Y-148005D01*
Y-149005D01*
X478134D01*
Y-146006D02*
X475135D01*
Y-144507D01*
X475635Y-144007D01*
X476634D01*
X477134Y-144507D01*
Y-146006D01*
X475635Y-141008D02*
X475135Y-141508D01*
Y-142507D01*
X475635Y-143007D01*
X477634D01*
X478134Y-142507D01*
Y-141508D01*
X477634Y-141008D01*
X476634D01*
Y-142007D01*
X478134Y-140008D02*
X476134D01*
X475135Y-139008D01*
X476134Y-138009D01*
X478134D01*
X476634D01*
Y-140008D01*
X504992Y-226698D02*
Y-227698D01*
X505492Y-228198D01*
X507491D01*
X507991Y-227698D01*
Y-226698D01*
X507491Y-226199D01*
X505492D01*
X504992Y-226698D01*
X507991Y-224699D02*
X505492D01*
X506492D01*
Y-225199D01*
Y-224199D01*
Y-224699D01*
X505492D01*
X504992Y-224199D01*
X507991Y-222200D02*
X505492D01*
X506492D01*
Y-222700D01*
Y-221700D01*
Y-222200D01*
X505492D01*
X504992Y-221700D01*
X507991Y-216702D02*
X505492D01*
X506492D01*
Y-217201D01*
Y-216202D01*
Y-216702D01*
X505492D01*
X504992Y-216202D01*
X507991Y-214202D02*
Y-213203D01*
X507491Y-212703D01*
X506492D01*
X505992Y-213203D01*
Y-214202D01*
X506492Y-214702D01*
X507491D01*
X507991Y-214202D01*
X505992Y-211703D02*
X507991D01*
X506991D01*
X506492Y-211203D01*
X505992Y-210703D01*
Y-210204D01*
X504992Y-205705D02*
X507991D01*
Y-204206D01*
X507491Y-203706D01*
X505492D01*
X504992Y-204206D01*
Y-205705D01*
X507991Y-202706D02*
Y-201706D01*
Y-202206D01*
X505992D01*
Y-202706D01*
X507991Y-199707D02*
X505492D01*
X506492D01*
Y-200207D01*
Y-199207D01*
Y-199707D01*
X505492D01*
X504992Y-199207D01*
X507991Y-197208D02*
X505492D01*
X506492D01*
Y-197708D01*
Y-196708D01*
Y-197208D01*
X505492D01*
X504992Y-196708D01*
X507991Y-192209D02*
X504992D01*
Y-190710D01*
X505492Y-190210D01*
X506492D01*
X506991Y-190710D01*
Y-192209D01*
X507991Y-189210D02*
X504992D01*
Y-187711D01*
X505492Y-187211D01*
X506492D01*
X506991Y-187711D01*
Y-189210D01*
X505492Y-184212D02*
X504992Y-184712D01*
Y-185712D01*
X505492Y-186211D01*
X505992D01*
X506492Y-185712D01*
Y-184712D01*
X506991Y-184212D01*
X507491D01*
X507991Y-184712D01*
Y-185712D01*
X507491Y-186211D01*
X507991Y-179214D02*
X506991Y-180213D01*
X505992D01*
X504992Y-179214D01*
X505492Y-175715D02*
X504992Y-176215D01*
Y-177214D01*
X505492Y-177714D01*
X505992D01*
X506492Y-177214D01*
Y-176215D01*
X506991Y-175715D01*
X507491D01*
X507991Y-176215D01*
Y-177214D01*
X507491Y-177714D01*
X507991Y-174715D02*
X505992D01*
X504992Y-173715D01*
X505992Y-172716D01*
X507991D01*
X506492D01*
Y-174715D01*
X504992Y-169717D02*
Y-171716D01*
X506492D01*
X505992Y-170716D01*
Y-170217D01*
X506492Y-169717D01*
X507491D01*
X507991Y-170217D01*
Y-171216D01*
X507491Y-171716D01*
X505492Y-168717D02*
X504992Y-168217D01*
Y-167218D01*
X505492Y-166718D01*
X505992D01*
X506492Y-167218D01*
Y-167717D01*
Y-167218D01*
X506991Y-166718D01*
X507491D01*
X507991Y-167218D01*
Y-168217D01*
X507491Y-168717D01*
X500581Y-228414D02*
X503580D01*
Y-226415D01*
X500581Y-223416D02*
Y-225415D01*
X503580D01*
Y-223416D01*
X502080Y-225415D02*
Y-224416D01*
X500581Y-222416D02*
X503580D01*
Y-220917D01*
X503080Y-220417D01*
X501080D01*
X500581Y-220917D01*
Y-222416D01*
X503580Y-215419D02*
X502580Y-216418D01*
X501580D01*
X500581Y-215419D01*
Y-213919D02*
X503580D01*
Y-212420D01*
X503080Y-211920D01*
X501080D01*
X500581Y-212420D01*
Y-213919D01*
X503580Y-208921D02*
Y-210920D01*
X501580Y-208921D01*
X501080D01*
X500581Y-209420D01*
Y-210420D01*
X501080Y-210920D01*
X503580Y-205922D02*
Y-207921D01*
X501580Y-205922D01*
X501080D01*
X500581Y-206421D01*
Y-207421D01*
X501080Y-207921D01*
X503580Y-204922D02*
X502580Y-203922D01*
X501580D01*
X500581Y-204922D01*
Y-197924D02*
Y-198924D01*
X501080Y-199424D01*
X503080D01*
X503580Y-198924D01*
Y-197924D01*
X503080Y-197424D01*
X501080D01*
X500581Y-197924D01*
X503580Y-196425D02*
X501580D01*
Y-194925D01*
X502080Y-194425D01*
X503580D01*
Y-189927D02*
X501080D01*
X502080D01*
Y-190427D01*
Y-189427D01*
Y-189927D01*
X501080D01*
X500581Y-189427D01*
X503580Y-187427D02*
Y-186428D01*
X503080Y-185928D01*
X502080D01*
X501580Y-186428D01*
Y-187427D01*
X502080Y-187927D01*
X503080D01*
X503580Y-187427D01*
X501580Y-184928D02*
X503580D01*
X502580D01*
X502080Y-184429D01*
X501580Y-183929D01*
Y-183429D01*
X501080Y-176931D02*
X500581Y-177431D01*
Y-178430D01*
X501080Y-178930D01*
X501580D01*
X502080Y-178430D01*
Y-177431D01*
X502580Y-176931D01*
X503080D01*
X503580Y-177431D01*
Y-178430D01*
X503080Y-178930D01*
X500581Y-173932D02*
Y-175931D01*
X503580D01*
Y-173932D01*
X502080Y-175931D02*
Y-174932D01*
X503580Y-169933D02*
X500581D01*
Y-168434D01*
X501080Y-167934D01*
X502080D01*
X502580Y-168434D01*
Y-169933D01*
X503580Y-166934D02*
X500581D01*
Y-165435D01*
X501080Y-164935D01*
X502080D01*
X502580Y-165435D01*
Y-166934D01*
X501080Y-161936D02*
X500581Y-162436D01*
Y-163435D01*
X501080Y-163935D01*
X501580D01*
X502080Y-163435D01*
Y-162436D01*
X502580Y-161936D01*
X503080D01*
X503580Y-162436D01*
Y-163435D01*
X503080Y-163935D01*
X503580Y-156937D02*
X502580Y-157937D01*
X501580D01*
X500581Y-156937D01*
X503580Y-155438D02*
X500581D01*
X501580Y-154438D01*
X500581Y-153439D01*
X503580D01*
Y-151939D02*
Y-150939D01*
X503080Y-150440D01*
X502080D01*
X501580Y-150939D01*
Y-151939D01*
X502080Y-152439D01*
X503080D01*
X503580Y-151939D01*
Y-149440D02*
Y-147940D01*
X503080Y-147441D01*
X502580Y-147940D01*
Y-148940D01*
X502080Y-149440D01*
X501580Y-148940D01*
Y-147441D01*
X501080Y-145941D02*
X501580D01*
Y-146441D01*
Y-145441D01*
Y-145941D01*
X503080D01*
X503580Y-145441D01*
X501580Y-138943D02*
Y-140443D01*
X502080Y-140943D01*
X503080D01*
X503580Y-140443D01*
Y-138943D01*
Y-137444D02*
Y-136444D01*
X503080Y-135944D01*
X502080D01*
X501580Y-136444D01*
Y-137444D01*
X502080Y-137944D01*
X503080D01*
X503580Y-137444D01*
Y-134944D02*
X501580D01*
Y-134445D01*
X502080Y-133945D01*
X503580D01*
X502080D01*
X501580Y-133445D01*
X502080Y-132945D01*
X503580D01*
Y-131946D02*
X501580D01*
Y-131446D01*
X502080Y-130946D01*
X503580D01*
X502080D01*
X501580Y-130446D01*
X502080Y-129946D01*
X503580D01*
Y-128447D02*
Y-127447D01*
X503080Y-126947D01*
X502080D01*
X501580Y-127447D01*
Y-128447D01*
X502080Y-128946D01*
X503080D01*
X503580Y-128447D01*
Y-125947D02*
X501580D01*
Y-124448D01*
X502080Y-123948D01*
X503580D01*
Y-122948D02*
X502580Y-121949D01*
X501580D01*
X500581Y-122948D01*
X92989Y-30496D02*
X92489Y-29996D01*
X91489D01*
X90989Y-30496D01*
Y-32496D01*
X91489Y-32996D01*
X92489D01*
X92989Y-32496D01*
X93988Y-29996D02*
X95988D01*
Y-30496D01*
X93988Y-32496D01*
Y-32996D01*
X96987D02*
X97987D01*
X97487D01*
Y-29996D01*
X96987Y-30496D01*
D19*
X266256Y-119732D02*
Y-113732D01*
X258656Y-119732D02*
Y-113732D01*
X484946Y-299174D02*
Y-297337D01*
X483109Y-310537D02*
X484946D01*
X471746D02*
Y-308700D01*
Y-299174D02*
Y-297337D01*
X483109D02*
X484946D01*
Y-310537D02*
Y-308700D01*
X471746Y-310537D02*
X473584D01*
X471746Y-297337D02*
X473584D01*
X157387Y5156D02*
Y6994D01*
X155550Y-6206D02*
X157387D01*
X144187D02*
Y-4369D01*
Y5156D02*
Y6994D01*
X155550D02*
X157387D01*
Y-6206D02*
Y-4369D01*
X144187Y-6206D02*
X146025D01*
X144187Y6994D02*
X146025D01*
X578448Y-24454D02*
Y-22914D01*
X553048Y-34364D02*
Y-22914D01*
X549048Y-34364D02*
X553048D01*
X549048Y-38864D02*
Y-34364D01*
Y-38864D02*
X553048D01*
Y-50314D02*
Y-38864D01*
Y-50314D02*
X578448D01*
Y-48774D01*
X553048Y-22914D02*
X578448D01*
X108459Y-26079D02*
X112857D01*
X88257D02*
Y-21681D01*
Y-1479D02*
X92656D01*
X108459D02*
X112857D01*
Y-26079D02*
Y-21681D01*
X88257Y-26079D02*
X92656D01*
X88257Y-5878D02*
Y-1479D01*
X112857Y-5878D02*
Y-1479D01*
X409747Y-128343D02*
Y-123944D01*
Y-103743D02*
X414146D01*
X434347Y-108142D02*
Y-103743D01*
Y-128343D02*
Y-123944D01*
X409747Y-128343D02*
X414146D01*
X409747Y-108142D02*
Y-103743D01*
X429948D02*
X434347D01*
X429948Y-128343D02*
X434347D01*
X485378Y-359620D02*
Y-353620D01*
X440890Y-358832D02*
Y-352832D01*
X525276Y-359296D02*
Y-353296D01*
X569764Y-359690D02*
Y-353690D01*
X617066Y-42370D02*
Y-36370D01*
X624666Y-42370D02*
Y-36370D01*
X588583Y-38189D02*
X592520D01*
D20*
X16535Y0D02*
X17717D01*
X19685D02*
X20866D01*
X17717Y-1181D02*
Y1181D01*
X19685Y-1181D02*
Y1181D01*
X17717Y0D02*
X19685Y1181D01*
X17717Y0D02*
X19685Y-1181D01*
X16142Y6693D02*
X17323D01*
X19291D02*
X20472D01*
X17323Y5512D02*
Y7874D01*
X19291Y5512D02*
Y7874D01*
X17323Y6693D02*
X19291Y7874D01*
X17323Y6693D02*
X19291Y5512D01*
X15748Y13780D02*
X16929D01*
X18898D02*
X20079D01*
X16929Y12598D02*
Y14961D01*
X18898Y12598D02*
Y14961D01*
X16929Y13780D02*
X18898Y14961D01*
X16929Y13780D02*
X18898Y12598D01*
X15354Y19291D02*
X16535D01*
X18504D02*
X19685D01*
X16535Y18110D02*
Y20472D01*
X18504Y18110D02*
Y20472D01*
X16535Y19291D02*
X18504Y20472D01*
X16535Y19291D02*
X18504Y18110D01*
X35597Y-4350D02*
X37566Y-5531D01*
X35597Y-4350D02*
X37566Y-3169D01*
Y-5531D02*
Y-3169D01*
X35597Y-5531D02*
Y-3169D01*
X37566Y-4350D02*
X38747D01*
X34416D02*
X35597D01*
X34646Y5906D02*
X36614Y4724D01*
X34646Y5906D02*
X36614Y7087D01*
Y4724D02*
Y7087D01*
X34646Y4724D02*
Y7087D01*
X36614Y5906D02*
X37795D01*
X33465D02*
X34646D01*
Y12598D02*
X36614Y11417D01*
X34646Y12598D02*
X36614Y13780D01*
Y11417D02*
Y13780D01*
X34646Y11417D02*
Y13780D01*
X36614Y12598D02*
X37795D01*
X33465D02*
X34646D01*
X-18504Y-123622D02*
X-17323Y-121653D01*
X-16142Y-123622D01*
X-18504D02*
X-16142D01*
X-18504Y-121653D02*
X-16142D01*
X-17323Y-124803D02*
Y-123622D01*
Y-121653D02*
Y-120472D01*
X-18504Y-80315D02*
X-17323Y-78347D01*
X-16142Y-80315D01*
X-18504D02*
X-16142D01*
X-18504Y-78347D02*
X-16142D01*
X-17323Y-81496D02*
Y-80315D01*
Y-78347D02*
Y-77165D01*
X467297Y-298335D02*
X470629Y-301667D01*
X467297D02*
X470629Y-298335D01*
X467297Y-300001D02*
X470629D01*
X468963Y-301667D02*
Y-298335D01*
X139737Y5996D02*
X143070Y2664D01*
X139737D02*
X143070Y5996D01*
X139737Y4330D02*
X143070D01*
X141403Y2664D02*
Y5996D01*
X547113Y-14864D02*
X543781Y-18196D01*
Y-14864D02*
X547113Y-18196D01*
X545447Y-14864D02*
Y-18196D01*
X543781Y-16530D02*
X547113D01*
X110628Y-18504D02*
X107296Y-21836D01*
Y-18504D02*
X110628Y-21836D01*
X108962Y-18504D02*
Y-21836D01*
X107296Y-20170D02*
X110628D01*
X437197Y-124008D02*
X433865Y-120676D01*
X437197D02*
X433865Y-124008D01*
X437197Y-122342D02*
X433865D01*
X435531Y-120676D02*
Y-124008D01*
D21*
X120581Y-77214D02*
Y-45718D01*
X156014Y-77214D02*
Y-45718D01*
X120581D02*
X156014D01*
X120581Y-77214D02*
X156014D01*
X533219Y-337884D02*
X564715D01*
X533219Y-302451D02*
X564715D01*
X533219Y-337884D02*
Y-302451D01*
X564715Y-337884D02*
Y-302451D01*
D22*
X308966Y-173895D02*
X311592D01*
X308966Y-176257D02*
Y-173895D01*
X306801Y-176257D02*
X308966D01*
X306801Y-187281D02*
Y-176257D01*
X390592Y-173895D02*
X393218D01*
Y-176257D02*
Y-173895D01*
Y-176257D02*
X395383D01*
Y-187281D02*
Y-176257D01*
X390592Y-189643D02*
X393218D01*
X308966D02*
X311592D01*
X306801Y-187281D02*
X308966Y-189643D01*
X393218D02*
X395383Y-187281D01*
X306791Y-324378D02*
X308956Y-322016D01*
X393208D02*
X395373Y-324378D01*
X390582Y-322016D02*
X393208D01*
X308956D02*
X311582D01*
X306791Y-335402D02*
Y-324378D01*
Y-335402D02*
X308956D01*
Y-337764D02*
Y-335402D01*
Y-337764D02*
X311582D01*
X395373Y-335402D02*
Y-324378D01*
X393208Y-335402D02*
X395373D01*
X393208Y-337764D02*
Y-335402D01*
X390582Y-337764D02*
X393208D01*
X266594Y-211041D02*
X268956Y-213206D01*
X266594Y-299623D02*
X268956Y-297458D01*
Y-294832D01*
Y-215832D02*
Y-213206D01*
X255570Y-211041D02*
X266594D01*
X255570Y-213206D02*
Y-211041D01*
X253208Y-213206D02*
X255570D01*
X253208Y-215832D02*
Y-213206D01*
X255570Y-299623D02*
X266594D01*
X255570D02*
Y-297458D01*
X253208D02*
X255570D01*
X253208D02*
Y-294832D01*
X440699Y-297468D02*
X443061Y-299633D01*
X440699Y-213216D02*
X443061Y-211051D01*
X440699Y-215842D02*
Y-213216D01*
Y-297468D02*
Y-294842D01*
X443061Y-299633D02*
X454085D01*
Y-297468D01*
X456447D01*
Y-294842D01*
X443061Y-211051D02*
X454085D01*
Y-213216D02*
Y-211051D01*
Y-213216D02*
X456447D01*
Y-215842D02*
Y-213216D01*
D23*
X-16437Y-185433D02*
Y-179134D01*
Y-68307D02*
Y-62008D01*
Y-238189D02*
Y-231890D01*
Y-291732D02*
Y-285433D01*
Y-344488D02*
Y-338189D01*
Y-111614D02*
Y-105315D01*
D24*
X244698Y-152565D02*
X245364Y-151899D01*
X246697D01*
X247363Y-152565D01*
Y-153232D01*
X246697Y-153898D01*
X246030D01*
X246697D01*
X247363Y-154565D01*
Y-155231D01*
X246697Y-155897D01*
X245364D01*
X244698Y-155231D01*
X248696Y-155897D02*
Y-155231D01*
X249363D01*
Y-155897D01*
X248696D01*
X252029Y-152565D02*
X252695Y-151899D01*
X254028D01*
X254694Y-152565D01*
Y-153232D01*
X254028Y-153898D01*
X253362D01*
X254028D01*
X254694Y-154565D01*
Y-155231D01*
X254028Y-155897D01*
X252695D01*
X252029Y-155231D01*
X256027Y-151899D02*
Y-154565D01*
X257360Y-155897D01*
X258693Y-154565D01*
Y-151899D01*
X248448Y-139590D02*
X245782D01*
Y-141589D01*
X247115Y-140922D01*
X247781D01*
X248448Y-141589D01*
Y-142922D01*
X247781Y-143588D01*
X246448D01*
X245782Y-142922D01*
X249781Y-139590D02*
Y-142255D01*
X251114Y-143588D01*
X252446Y-142255D01*
Y-139590D01*
X250113Y-163548D02*
Y-160549D01*
X251112Y-161549D01*
X252112Y-160549D01*
Y-163548D01*
X253112D02*
Y-161549D01*
X254111Y-160549D01*
X255111Y-161549D01*
Y-163548D01*
Y-162048D01*
X253112D01*
X258110Y-161049D02*
X257610Y-160549D01*
X256610D01*
X256111Y-161049D01*
Y-163048D01*
X256610Y-163548D01*
X257610D01*
X258110Y-163048D01*
X262109Y-163548D02*
Y-160549D01*
X263608D01*
X264108Y-161049D01*
Y-162048D01*
X263608Y-162548D01*
X262109D01*
X265108Y-160549D02*
Y-163548D01*
X266107Y-162548D01*
X267107Y-163548D01*
Y-160549D01*
X268107Y-163548D02*
Y-160549D01*
X269606D01*
X270106Y-161049D01*
Y-162048D01*
X269606Y-162548D01*
X268107D01*
X269106D02*
X270106Y-163548D01*
X276104Y-161049D02*
X275604Y-160549D01*
X274605D01*
X274105Y-161049D01*
Y-161549D01*
X274605Y-162048D01*
X275604D01*
X276104Y-162548D01*
Y-163048D01*
X275604Y-163548D01*
X274605D01*
X274105Y-163048D01*
X279103Y-160549D02*
X277104D01*
Y-163548D01*
X279103D01*
X277104Y-162048D02*
X278103D01*
X280103Y-160549D02*
Y-163548D01*
X282102D01*
X157020Y-72846D02*
Y-73846D01*
X157520Y-74346D01*
X159520D01*
X160020Y-73846D01*
Y-72846D01*
X159520Y-72346D01*
X157520D01*
X157020Y-72846D01*
X158020Y-71347D02*
X160020D01*
X159020D01*
X158520Y-70847D01*
X158020Y-70347D01*
Y-69847D01*
X160020Y-68348D02*
Y-67348D01*
Y-67848D01*
X158020D01*
Y-68348D01*
X161019Y-64849D02*
Y-64349D01*
X160519Y-63849D01*
X158020D01*
Y-65349D01*
X158520Y-65848D01*
X159520D01*
X160020Y-65349D01*
Y-63849D01*
Y-57851D02*
Y-59850D01*
X158020Y-57851D01*
X157520D01*
X157020Y-58351D01*
Y-59351D01*
X157520Y-59850D01*
X158020Y-56851D02*
X160020Y-54852D01*
X159020Y-55852D01*
X158020Y-54852D01*
X160020Y-56851D01*
Y-52353D02*
X157020D01*
X158520Y-53852D01*
Y-51853D01*
X540363Y-302375D02*
X539364D01*
X538864Y-302875D01*
Y-304874D01*
X539364Y-305374D01*
X540363D01*
X540863Y-304874D01*
Y-302875D01*
X540363Y-302375D01*
X541863Y-303375D02*
Y-305374D01*
Y-304374D01*
X542363Y-303874D01*
X542863Y-303375D01*
X543362D01*
X544862Y-305374D02*
X545862D01*
X545362D01*
Y-303375D01*
X544862D01*
X548361Y-306374D02*
X548861D01*
X549360Y-305874D01*
Y-303375D01*
X547861D01*
X547361Y-303874D01*
Y-304874D01*
X547861Y-305374D01*
X549360D01*
X555359D02*
X553359D01*
X555359Y-303375D01*
Y-302875D01*
X554859Y-302375D01*
X553859D01*
X553359Y-302875D01*
X556358Y-303375D02*
X558357Y-305374D01*
X557358Y-304374D01*
X558357Y-303375D01*
X556358Y-305374D01*
X560857D02*
Y-302375D01*
X559357Y-303874D01*
X561356D01*
X245388Y-130990D02*
X246721D01*
X246055D01*
Y-126991D01*
X245388Y-127657D01*
X251386Y-130990D02*
X248720D01*
X251386Y-128324D01*
Y-127657D01*
X250720Y-126991D01*
X249387D01*
X248720Y-127657D01*
X252719Y-126991D02*
Y-129657D01*
X254052Y-130990D01*
X255385Y-129657D01*
Y-126991D01*
X39908Y-73479D02*
X39408Y-73978D01*
Y-74978D01*
X39908Y-75478D01*
X41907D01*
X42407Y-74978D01*
Y-73978D01*
X41907Y-73479D01*
X40908D01*
Y-74478D01*
X42407Y-72479D02*
X39408D01*
X42407Y-70480D01*
X39408D01*
X39908Y-67480D02*
X39408Y-67980D01*
Y-68980D01*
X39908Y-69480D01*
X40408D01*
X40908Y-68980D01*
Y-67980D01*
X41407Y-67480D01*
X41907D01*
X42407Y-67980D01*
Y-68980D01*
X41907Y-69480D01*
X39908Y-64482D02*
X39408Y-64981D01*
Y-65981D01*
X39908Y-66481D01*
X40408D01*
X40908Y-65981D01*
Y-64981D01*
X41407Y-64482D01*
X41907D01*
X42407Y-64981D01*
Y-65981D01*
X41907Y-66481D01*
X42407Y-63482D02*
Y-62482D01*
Y-62982D01*
X39408D01*
X39908Y-63482D01*
X40302Y-114424D02*
X39802Y-114923D01*
Y-115923D01*
X40302Y-116423D01*
X42301D01*
X42801Y-115923D01*
Y-114923D01*
X42301Y-114424D01*
X41301D01*
Y-115423D01*
X42801Y-113424D02*
X39802D01*
X42801Y-111425D01*
X39802D01*
X40302Y-108425D02*
X39802Y-108925D01*
Y-109925D01*
X40302Y-110425D01*
X40801D01*
X41301Y-109925D01*
Y-108925D01*
X41801Y-108425D01*
X42301D01*
X42801Y-108925D01*
Y-109925D01*
X42301Y-110425D01*
X40302Y-105426D02*
X39802Y-105926D01*
Y-106926D01*
X40302Y-107426D01*
X40801D01*
X41301Y-106926D01*
Y-105926D01*
X41801Y-105426D01*
X42301D01*
X42801Y-105926D01*
Y-106926D01*
X42301Y-107426D01*
X42801Y-102427D02*
Y-104427D01*
X40801Y-102427D01*
X40302D01*
X39802Y-102927D01*
Y-103927D01*
X40302Y-104427D01*
X31755Y-118616D02*
Y-115617D01*
X33254D01*
X33754Y-116116D01*
Y-117116D01*
X33254Y-117616D01*
X31755D01*
X32754D02*
X33754Y-118616D01*
X34754D02*
X35753D01*
X35254D01*
Y-115617D01*
X34754Y-116116D01*
X37253Y-118616D02*
X38252D01*
X37753D01*
Y-115617D01*
X37253Y-116116D01*
X39752D02*
X40252Y-115617D01*
X41252D01*
X41751Y-116116D01*
Y-118116D01*
X41252Y-118616D01*
X40252D01*
X39752Y-118116D01*
Y-116116D01*
X31898Y-109167D02*
Y-106168D01*
X33398D01*
X33898Y-106668D01*
Y-107667D01*
X33398Y-108167D01*
X31898D01*
X32898D02*
X33898Y-109167D01*
X34897D02*
X35897D01*
X35397D01*
Y-106168D01*
X34897Y-106668D01*
X37397D02*
X37896Y-106168D01*
X38896D01*
X39396Y-106668D01*
Y-108667D01*
X38896Y-109167D01*
X37896D01*
X37397Y-108667D01*
Y-106668D01*
X40396Y-108667D02*
X40896Y-109167D01*
X41895D01*
X42395Y-108667D01*
Y-106668D01*
X41895Y-106168D01*
X40896D01*
X40396Y-106668D01*
Y-107167D01*
X40896Y-107667D01*
X42395D01*
X31898Y-113891D02*
Y-110892D01*
X33398D01*
X33898Y-111392D01*
Y-112392D01*
X33398Y-112892D01*
X31898D01*
X32898D02*
X33898Y-113891D01*
X34897D02*
X35897D01*
X35397D01*
Y-110892D01*
X34897Y-111392D01*
X37397D02*
X37896Y-110892D01*
X38896D01*
X39396Y-111392D01*
Y-113391D01*
X38896Y-113891D01*
X37896D01*
X37397Y-113391D01*
Y-111392D01*
X40396D02*
X40896Y-110892D01*
X41895D01*
X42395Y-111392D01*
Y-111892D01*
X41895Y-112392D01*
X42395Y-112892D01*
Y-113391D01*
X41895Y-113891D01*
X40896D01*
X40396Y-113391D01*
Y-112892D01*
X40896Y-112392D01*
X40396Y-111892D01*
Y-111392D01*
X40896Y-112392D02*
X41895D01*
X291408Y-186739D02*
Y-183740D01*
X292908D01*
X293408Y-184240D01*
Y-185239D01*
X292908Y-185739D01*
X291408D01*
X292408D02*
X293408Y-186739D01*
X294408D02*
X295407D01*
X294907D01*
Y-183740D01*
X294408Y-184240D01*
X296907D02*
X297407Y-183740D01*
X298406D01*
X298906Y-184240D01*
Y-186239D01*
X298406Y-186739D01*
X297407D01*
X296907Y-186239D01*
Y-184240D01*
X299906Y-183740D02*
X301905D01*
Y-184240D01*
X299906Y-186239D01*
Y-186739D01*
X297114Y-196381D02*
Y-193382D01*
X298613D01*
X299113Y-193882D01*
Y-194882D01*
X298613Y-195382D01*
X297114D01*
X298114D02*
X299113Y-196381D01*
X300113D02*
X301113D01*
X300613D01*
Y-193382D01*
X300113Y-193882D01*
X302612D02*
X303112Y-193382D01*
X304112D01*
X304611Y-193882D01*
Y-195882D01*
X304112Y-196381D01*
X303112D01*
X302612Y-195882D01*
Y-193882D01*
X307611Y-193382D02*
X306611Y-193882D01*
X305611Y-194882D01*
Y-195882D01*
X306111Y-196381D01*
X307111D01*
X307611Y-195882D01*
Y-195382D01*
X307111Y-194882D01*
X305611D01*
X257731Y-197956D02*
Y-194957D01*
X259230D01*
X259730Y-195457D01*
Y-196457D01*
X259230Y-196957D01*
X257731D01*
X258731D02*
X259730Y-197956D01*
X260730D02*
X261730D01*
X261230D01*
Y-194957D01*
X260730Y-195457D01*
X263229D02*
X263729Y-194957D01*
X264728D01*
X265228Y-195457D01*
Y-197456D01*
X264728Y-197956D01*
X263729D01*
X263229Y-197456D01*
Y-195457D01*
X268227Y-194957D02*
X266228D01*
Y-196457D01*
X267228Y-195957D01*
X267728D01*
X268227Y-196457D01*
Y-197456D01*
X267728Y-197956D01*
X266728D01*
X266228Y-197456D01*
X257350Y-192838D02*
Y-189839D01*
X258850D01*
X259349Y-190339D01*
Y-191339D01*
X258850Y-191838D01*
X257350D01*
X258350D02*
X259349Y-192838D01*
X260349D02*
X261349D01*
X260849D01*
Y-189839D01*
X260349Y-190339D01*
X262848D02*
X263348Y-189839D01*
X264348D01*
X264848Y-190339D01*
Y-192338D01*
X264348Y-192838D01*
X263348D01*
X262848Y-192338D01*
Y-190339D01*
X267347Y-192838D02*
Y-189839D01*
X265847Y-191339D01*
X267847D01*
X313256Y-309373D02*
Y-306375D01*
X314755D01*
X315255Y-306874D01*
Y-307874D01*
X314755Y-308374D01*
X313256D01*
X314255D02*
X315255Y-309373D01*
X316255D02*
X317254D01*
X316755D01*
Y-306375D01*
X316255Y-306874D01*
X318754D02*
X319254Y-306375D01*
X320253D01*
X320753Y-306874D01*
Y-308874D01*
X320253Y-309373D01*
X319254D01*
X318754Y-308874D01*
Y-306874D01*
X321753D02*
X322253Y-306375D01*
X323252D01*
X323752Y-306874D01*
Y-307374D01*
X323252Y-307874D01*
X322753D01*
X323252D01*
X323752Y-308374D01*
Y-308874D01*
X323252Y-309373D01*
X322253D01*
X321753Y-308874D01*
X312862Y-280240D02*
Y-277241D01*
X314362D01*
X314861Y-277741D01*
Y-278740D01*
X314362Y-279240D01*
X312862D01*
X313862D02*
X314861Y-280240D01*
X315861D02*
X316861D01*
X316361D01*
Y-277241D01*
X315861Y-277741D01*
X318360D02*
X318860Y-277241D01*
X319860D01*
X320359Y-277741D01*
Y-279740D01*
X319860Y-280240D01*
X318860D01*
X318360Y-279740D01*
Y-277741D01*
X323358Y-280240D02*
X321359D01*
X323358Y-278240D01*
Y-277741D01*
X322859Y-277241D01*
X321859D01*
X321359Y-277741D01*
X338564Y-308436D02*
Y-305437D01*
X340064D01*
X340564Y-305937D01*
Y-306937D01*
X340064Y-307436D01*
X338564D01*
X339564D02*
X340564Y-308436D01*
X341563D02*
X342563D01*
X342063D01*
Y-305437D01*
X341563Y-305937D01*
X344063D02*
X344563Y-305437D01*
X345562D01*
X346062Y-305937D01*
Y-307936D01*
X345562Y-308436D01*
X344563D01*
X344063Y-307936D01*
Y-305937D01*
X347062Y-308436D02*
X348061D01*
X347562D01*
Y-305437D01*
X347062Y-305937D01*
X340846Y-268374D02*
X343845D01*
Y-269873D01*
X343345Y-270373D01*
X342346D01*
X341846Y-269873D01*
Y-268374D01*
Y-269373D02*
X340846Y-270373D01*
Y-271373D02*
Y-272373D01*
Y-271873D01*
X343845D01*
X343345Y-271373D01*
Y-273872D02*
X343845Y-274372D01*
Y-275372D01*
X343345Y-275871D01*
X341346D01*
X340846Y-275372D01*
Y-274372D01*
X341346Y-273872D01*
X343345D01*
Y-276871D02*
X343845Y-277371D01*
Y-278370D01*
X343345Y-278870D01*
X341346D01*
X340846Y-278370D01*
Y-277371D01*
X341346Y-276871D01*
X343345D01*
X266474Y-184721D02*
Y-187220D01*
X266974Y-187720D01*
X267973D01*
X268473Y-187220D01*
Y-184721D01*
X271472Y-187720D02*
X269473D01*
X271472Y-185721D01*
Y-185221D01*
X270972Y-184721D01*
X269973D01*
X269473Y-185221D01*
X272472D02*
X272972Y-184721D01*
X273971D01*
X274471Y-185221D01*
Y-185721D01*
X273971Y-186221D01*
X273471D01*
X273971D01*
X274471Y-186720D01*
Y-187220D01*
X273971Y-187720D01*
X272972D01*
X272472Y-187220D01*
X306232Y-282758D02*
Y-285258D01*
X306731Y-285757D01*
X307731D01*
X308231Y-285258D01*
Y-282758D01*
X311230Y-285757D02*
X309231D01*
X311230Y-283758D01*
Y-283258D01*
X310730Y-282758D01*
X309731D01*
X309231Y-283258D01*
X314229Y-285757D02*
X312230D01*
X314229Y-283758D01*
Y-283258D01*
X313729Y-282758D01*
X312730D01*
X312230Y-283258D01*
X337643Y-282807D02*
Y-285306D01*
X338143Y-285806D01*
X339142D01*
X339642Y-285306D01*
Y-282807D01*
X342641Y-285806D02*
X340642D01*
X342641Y-283806D01*
Y-283307D01*
X342141Y-282807D01*
X341142D01*
X340642Y-283307D01*
X343641Y-285806D02*
X344641D01*
X344141D01*
Y-282807D01*
X343641Y-283307D01*
X627484Y-237340D02*
X624985D01*
X624485Y-237840D01*
Y-238839D01*
X624985Y-239339D01*
X627484D01*
X624485Y-242338D02*
Y-240339D01*
X626484Y-242338D01*
X626984D01*
X627484Y-241838D01*
Y-240839D01*
X626984Y-240339D01*
Y-243338D02*
X627484Y-243838D01*
Y-244837D01*
X626984Y-245337D01*
X624985D01*
X624485Y-244837D01*
Y-243838D01*
X624985Y-243338D01*
X626984D01*
X625119Y-197085D02*
X624619Y-197585D01*
Y-198585D01*
X625119Y-199084D01*
X625619D01*
X626119Y-198585D01*
Y-197585D01*
X626619Y-197085D01*
X627119D01*
X627619Y-197585D01*
Y-198585D01*
X627119Y-199084D01*
X624619Y-196086D02*
X627619D01*
X626619Y-195086D01*
X627619Y-194086D01*
X624619D01*
X627619Y-193086D02*
Y-192087D01*
Y-192587D01*
X624619D01*
X625119Y-193086D01*
X284327Y-210568D02*
X287326D01*
Y-212068D01*
X286826Y-212568D01*
X285827D01*
X285327Y-212068D01*
Y-210568D01*
Y-211568D02*
X284327Y-212568D01*
X284827Y-213567D02*
X284327Y-214067D01*
Y-215067D01*
X284827Y-215567D01*
X286826D01*
X287326Y-215067D01*
Y-214067D01*
X286826Y-213567D01*
X286327D01*
X285827Y-214067D01*
Y-215567D01*
X284827Y-216566D02*
X284327Y-217066D01*
Y-218066D01*
X284827Y-218566D01*
X286826D01*
X287326Y-218066D01*
Y-217066D01*
X286826Y-216566D01*
X286327D01*
X285827Y-217066D01*
Y-218566D01*
X286539Y-181164D02*
X283540D01*
Y-179665D01*
X284040Y-179165D01*
X285039D01*
X285539Y-179665D01*
Y-181164D01*
Y-180164D02*
X286539Y-179165D01*
X286039Y-178165D02*
X286539Y-177665D01*
Y-176665D01*
X286039Y-176166D01*
X284040D01*
X283540Y-176665D01*
Y-177665D01*
X284040Y-178165D01*
X284540D01*
X285039Y-177665D01*
Y-176166D01*
X284040Y-175166D02*
X283540Y-174666D01*
Y-173667D01*
X284040Y-173167D01*
X284540D01*
X285039Y-173667D01*
X285539Y-173167D01*
X286039D01*
X286539Y-173667D01*
Y-174666D01*
X286039Y-175166D01*
X285539D01*
X285039Y-174666D01*
X284540Y-175166D01*
X284040D01*
X285039Y-174666D02*
Y-173667D01*
X278028Y-209781D02*
X281027D01*
Y-211280D01*
X280527Y-211780D01*
X279528D01*
X279028Y-211280D01*
Y-209781D01*
Y-210781D02*
X278028Y-211780D01*
X278528Y-212780D02*
X278028Y-213280D01*
Y-214279D01*
X278528Y-214779D01*
X280527D01*
X281027Y-214279D01*
Y-213280D01*
X280527Y-212780D01*
X280027D01*
X279528Y-213280D01*
Y-214779D01*
X281027Y-215779D02*
Y-217778D01*
X280527D01*
X278528Y-215779D01*
X278028D01*
X279452Y-181164D02*
X276453D01*
Y-179665D01*
X276953Y-179165D01*
X277953D01*
X278453Y-179665D01*
Y-181164D01*
Y-180164D02*
X279452Y-179165D01*
X278952Y-178165D02*
X279452Y-177665D01*
Y-176665D01*
X278952Y-176166D01*
X276953D01*
X276453Y-176665D01*
Y-177665D01*
X276953Y-178165D01*
X277453D01*
X277953Y-177665D01*
Y-176166D01*
X276453Y-173167D02*
X276953Y-174166D01*
X277953Y-175166D01*
X278952D01*
X279452Y-174666D01*
Y-173667D01*
X278952Y-173167D01*
X278453D01*
X277953Y-173667D01*
Y-175166D01*
X343639Y-244807D02*
Y-241808D01*
X345139D01*
X345638Y-242307D01*
Y-243307D01*
X345139Y-243807D01*
X343639D01*
X344639D02*
X345638Y-244807D01*
X346638Y-244307D02*
X347138Y-244807D01*
X348138D01*
X348638Y-244307D01*
Y-242307D01*
X348138Y-241808D01*
X347138D01*
X346638Y-242307D01*
Y-242807D01*
X347138Y-243307D01*
X348638D01*
X351637Y-241808D02*
X349637D01*
Y-243307D01*
X350637Y-242807D01*
X351137D01*
X351637Y-243307D01*
Y-244307D01*
X351137Y-244807D01*
X350137D01*
X349637Y-244307D01*
X303875Y-237326D02*
Y-234327D01*
X305375D01*
X305875Y-234827D01*
Y-235827D01*
X305375Y-236327D01*
X303875D01*
X304875D02*
X305875Y-237326D01*
X306874Y-236826D02*
X307374Y-237326D01*
X308374D01*
X308874Y-236826D01*
Y-234827D01*
X308374Y-234327D01*
X307374D01*
X306874Y-234827D01*
Y-235327D01*
X307374Y-235827D01*
X308874D01*
X311373Y-237326D02*
Y-234327D01*
X309873Y-235827D01*
X311873D01*
X295608Y-298744D02*
Y-295745D01*
X297107D01*
X297607Y-296244D01*
Y-297244D01*
X297107Y-297744D01*
X295608D01*
X296607D02*
X297607Y-298744D01*
X298607Y-298244D02*
X299107Y-298744D01*
X300106D01*
X300606Y-298244D01*
Y-296244D01*
X300106Y-295745D01*
X299107D01*
X298607Y-296244D01*
Y-296744D01*
X299107Y-297244D01*
X300606D01*
X301606Y-296244D02*
X302105Y-295745D01*
X303105D01*
X303605Y-296244D01*
Y-296744D01*
X303105Y-297244D01*
X302605D01*
X303105D01*
X303605Y-297744D01*
Y-298244D01*
X303105Y-298744D01*
X302105D01*
X301606Y-298244D01*
X329846Y-312660D02*
X326847D01*
Y-311161D01*
X327347Y-310661D01*
X328346D01*
X328846Y-311161D01*
Y-312660D01*
Y-311660D02*
X329846Y-310661D01*
X329346Y-309661D02*
X329846Y-309161D01*
Y-308162D01*
X329346Y-307662D01*
X327347D01*
X326847Y-308162D01*
Y-309161D01*
X327347Y-309661D01*
X327847D01*
X328346Y-309161D01*
Y-307662D01*
X329846Y-304663D02*
Y-306662D01*
X327847Y-304663D01*
X327347D01*
X326847Y-305163D01*
Y-306162D01*
X327347Y-306662D01*
X296895Y-290476D02*
Y-287477D01*
X298394D01*
X298894Y-287977D01*
Y-288976D01*
X298394Y-289476D01*
X296895D01*
X297895D02*
X298894Y-290476D01*
X299894Y-289976D02*
X300394Y-290476D01*
X301393D01*
X301893Y-289976D01*
Y-287977D01*
X301393Y-287477D01*
X300394D01*
X299894Y-287977D01*
Y-288476D01*
X300394Y-288976D01*
X301893D01*
X302893Y-290476D02*
X303893D01*
X303393D01*
Y-287477D01*
X302893Y-287977D01*
X326453Y-271198D02*
X329452D01*
Y-272698D01*
X328952Y-273198D01*
X327953D01*
X327453Y-272698D01*
Y-271198D01*
Y-272198D02*
X326453Y-273198D01*
X326953Y-274197D02*
X326453Y-274697D01*
Y-275697D01*
X326953Y-276197D01*
X328952D01*
X329452Y-275697D01*
Y-274697D01*
X328952Y-274197D01*
X328453D01*
X327953Y-274697D01*
Y-276197D01*
X328952Y-277196D02*
X329452Y-277696D01*
Y-278696D01*
X328952Y-279196D01*
X326953D01*
X326453Y-278696D01*
Y-277696D01*
X326953Y-277196D01*
X328952D01*
X335752Y-312266D02*
X332752D01*
Y-310767D01*
X333252Y-310267D01*
X334252D01*
X334752Y-310767D01*
Y-312266D01*
Y-311267D02*
X335752Y-310267D01*
X333252Y-309267D02*
X332752Y-308768D01*
Y-307768D01*
X333252Y-307268D01*
X333752D01*
X334252Y-307768D01*
X334752Y-307268D01*
X335252D01*
X335752Y-307768D01*
Y-308768D01*
X335252Y-309267D01*
X334752D01*
X334252Y-308768D01*
X333752Y-309267D01*
X333252D01*
X334252Y-308768D02*
Y-307768D01*
X332752Y-306268D02*
Y-304269D01*
X333252D01*
X335252Y-306268D01*
X335752D01*
X347182Y-301893D02*
Y-298894D01*
X348682D01*
X349182Y-299394D01*
Y-300394D01*
X348682Y-300893D01*
X347182D01*
X348182D02*
X349182Y-301893D01*
X350181Y-299394D02*
X350681Y-298894D01*
X351681D01*
X352181Y-299394D01*
Y-299894D01*
X351681Y-300394D01*
X352181Y-300893D01*
Y-301393D01*
X351681Y-301893D01*
X350681D01*
X350181Y-301393D01*
Y-300893D01*
X350681Y-300394D01*
X350181Y-299894D01*
Y-299394D01*
X350681Y-300394D02*
X351681D01*
X355180Y-298894D02*
X354180Y-299394D01*
X353181Y-300394D01*
Y-301393D01*
X353680Y-301893D01*
X354680D01*
X355180Y-301393D01*
Y-300893D01*
X354680Y-300394D01*
X353181D01*
X331571Y-271198D02*
X334570D01*
Y-272698D01*
X334071Y-273198D01*
X333071D01*
X332571Y-272698D01*
Y-271198D01*
Y-272198D02*
X331571Y-273198D01*
X334071Y-274197D02*
X334570Y-274697D01*
Y-275697D01*
X334071Y-276197D01*
X333571D01*
X333071Y-275697D01*
X332571Y-276197D01*
X332071D01*
X331571Y-275697D01*
Y-274697D01*
X332071Y-274197D01*
X332571D01*
X333071Y-274697D01*
X333571Y-274197D01*
X334071D01*
X333071Y-274697D02*
Y-275697D01*
X334570Y-279196D02*
Y-277196D01*
X333071D01*
X333571Y-278196D01*
Y-278696D01*
X333071Y-279196D01*
X332071D01*
X331571Y-278696D01*
Y-277696D01*
X332071Y-277196D01*
X347576Y-285752D02*
Y-282752D01*
X349076D01*
X349575Y-283252D01*
Y-284252D01*
X349076Y-284752D01*
X347576D01*
X348576D02*
X349575Y-285752D01*
X350575Y-283252D02*
X351075Y-282752D01*
X352075D01*
X352574Y-283252D01*
Y-283752D01*
X352075Y-284252D01*
X352574Y-284752D01*
Y-285252D01*
X352075Y-285752D01*
X351075D01*
X350575Y-285252D01*
Y-284752D01*
X351075Y-284252D01*
X350575Y-283752D01*
Y-283252D01*
X351075Y-284252D02*
X352075D01*
X355074Y-285752D02*
Y-282752D01*
X353574Y-284252D01*
X355574D01*
X597182Y-259767D02*
Y-256768D01*
X598682D01*
X599182Y-257268D01*
Y-258268D01*
X598682Y-258768D01*
X597182D01*
X598182D02*
X599182Y-259767D01*
X600181Y-257268D02*
X600681Y-256768D01*
X601681D01*
X602181Y-257268D01*
Y-257768D01*
X601681Y-258268D01*
X602181Y-258768D01*
Y-259267D01*
X601681Y-259767D01*
X600681D01*
X600181Y-259267D01*
Y-258768D01*
X600681Y-258268D01*
X600181Y-257768D01*
Y-257268D01*
X600681Y-258268D02*
X601681D01*
X603181Y-257268D02*
X603680Y-256768D01*
X604680D01*
X605180Y-257268D01*
Y-257768D01*
X604680Y-258268D01*
X604180D01*
X604680D01*
X605180Y-258768D01*
Y-259267D01*
X604680Y-259767D01*
X603680D01*
X603181Y-259267D01*
X597182Y-254649D02*
Y-251650D01*
X598682D01*
X599182Y-252150D01*
Y-253150D01*
X598682Y-253649D01*
X597182D01*
X598182D02*
X599182Y-254649D01*
X600181Y-252150D02*
X600681Y-251650D01*
X601681D01*
X602181Y-252150D01*
Y-252650D01*
X601681Y-253150D01*
X602181Y-253649D01*
Y-254149D01*
X601681Y-254649D01*
X600681D01*
X600181Y-254149D01*
Y-253649D01*
X600681Y-253150D01*
X600181Y-252650D01*
Y-252150D01*
X600681Y-253150D02*
X601681D01*
X605180Y-254649D02*
X603181D01*
X605180Y-252650D01*
Y-252150D01*
X604680Y-251650D01*
X603680D01*
X603181Y-252150D01*
X584296Y-240082D02*
Y-237083D01*
X585796D01*
X586296Y-237583D01*
Y-238583D01*
X585796Y-239083D01*
X584296D01*
X585296D02*
X586296Y-240082D01*
X587295Y-237583D02*
X587795Y-237083D01*
X588795D01*
X589295Y-237583D01*
Y-238083D01*
X588795Y-238583D01*
X589295Y-239083D01*
Y-239582D01*
X588795Y-240082D01*
X587795D01*
X587295Y-239582D01*
Y-239083D01*
X587795Y-238583D01*
X587295Y-238083D01*
Y-237583D01*
X587795Y-238583D02*
X588795D01*
X590295Y-240082D02*
X591294D01*
X590794D01*
Y-237083D01*
X590295Y-237583D01*
X587083Y-298894D02*
X585084D01*
Y-300394D01*
X586084D01*
X585084D01*
Y-301893D01*
X588083Y-298894D02*
Y-301893D01*
X589582D01*
X590082Y-301393D01*
Y-300893D01*
X589582Y-300394D01*
X588083D01*
X589582D01*
X590082Y-299894D01*
Y-299394D01*
X589582Y-298894D01*
X588083D01*
X591082Y-301893D02*
X592081D01*
X591582D01*
Y-298894D01*
X591082Y-299394D01*
X582222Y-218579D02*
Y-221578D01*
X583721D01*
X584221Y-221078D01*
Y-219079D01*
X583721Y-218579D01*
X582222D01*
X587220Y-221578D02*
X585221D01*
X587220Y-219579D01*
Y-219079D01*
X586720Y-218579D01*
X585721D01*
X585221Y-219079D01*
X589719Y-221578D02*
Y-218579D01*
X588220Y-220079D01*
X590219D01*
X599682Y-261599D02*
X599182Y-261099D01*
X598182D01*
X597682Y-261599D01*
Y-263598D01*
X598182Y-264098D01*
X599182D01*
X599682Y-263598D01*
X600681D02*
X601181Y-264098D01*
X602181D01*
X602681Y-263598D01*
Y-261599D01*
X602181Y-261099D01*
X601181D01*
X600681Y-261599D01*
Y-262099D01*
X601181Y-262598D01*
X602681D01*
X603680Y-264098D02*
X604680D01*
X604180D01*
Y-261099D01*
X603680Y-261599D01*
X622016Y-302150D02*
X621517Y-301650D01*
X620517D01*
X620017Y-302150D01*
Y-304149D01*
X620517Y-304649D01*
X621517D01*
X622016Y-304149D01*
X623016Y-302150D02*
X623516Y-301650D01*
X624516D01*
X625015Y-302150D01*
Y-302650D01*
X624516Y-303150D01*
X625015Y-303649D01*
Y-304149D01*
X624516Y-304649D01*
X623516D01*
X623016Y-304149D01*
Y-303649D01*
X623516Y-303150D01*
X623016Y-302650D01*
Y-302150D01*
X623516Y-303150D02*
X624516D01*
X626015Y-304149D02*
X626515Y-304649D01*
X627515D01*
X628015Y-304149D01*
Y-302150D01*
X627515Y-301650D01*
X626515D01*
X626015Y-302150D01*
Y-302650D01*
X626515Y-303150D01*
X628015D01*
X585796Y-291126D02*
X585296Y-290627D01*
X584296D01*
X583797Y-291126D01*
Y-293126D01*
X584296Y-293625D01*
X585296D01*
X585796Y-293126D01*
X586796Y-291126D02*
X587295Y-290627D01*
X588295D01*
X588795Y-291126D01*
Y-291626D01*
X588295Y-292126D01*
X588795Y-292626D01*
Y-293126D01*
X588295Y-293625D01*
X587295D01*
X586796Y-293126D01*
Y-292626D01*
X587295Y-292126D01*
X586796Y-291626D01*
Y-291126D01*
X587295Y-292126D02*
X588295D01*
X591794Y-290627D02*
X590794Y-291126D01*
X589795Y-292126D01*
Y-293126D01*
X590295Y-293625D01*
X591294D01*
X591794Y-293126D01*
Y-292626D01*
X591294Y-292126D01*
X589795D01*
X539052Y-69747D02*
X542051D01*
Y-68247D01*
X541551Y-67747D01*
X539551D01*
X539052Y-68247D01*
Y-69747D01*
X542051Y-64748D02*
Y-66748D01*
X540051Y-64748D01*
X539551D01*
X539052Y-65248D01*
Y-66248D01*
X539551Y-66748D01*
Y-63749D02*
X539052Y-63249D01*
Y-62249D01*
X539551Y-61749D01*
X540051D01*
X540551Y-62249D01*
Y-62749D01*
Y-62249D01*
X541051Y-61749D01*
X541551D01*
X542051Y-62249D01*
Y-63249D01*
X541551Y-63749D01*
X466080Y-71578D02*
Y-68579D01*
X467580D01*
X468079Y-69079D01*
Y-70079D01*
X467580Y-70579D01*
X466080D01*
X467080D02*
X468079Y-71578D01*
X469079Y-68579D02*
X471078D01*
Y-69079D01*
X469079Y-71078D01*
Y-71578D01*
X472078Y-68579D02*
X474078D01*
Y-69079D01*
X472078Y-71078D01*
Y-71578D01*
X450332Y-68973D02*
Y-71972D01*
X451831D01*
X452331Y-71472D01*
Y-69473D01*
X451831Y-68973D01*
X450332D01*
X455330Y-71972D02*
X453331D01*
X455330Y-69973D01*
Y-69473D01*
X454831Y-68973D01*
X453831D01*
X453331Y-69473D01*
X456330D02*
X456830Y-68973D01*
X457830D01*
X458329Y-69473D01*
Y-71472D01*
X457830Y-71972D01*
X456830D01*
X456330Y-71472D01*
Y-69473D01*
X582325Y-225272D02*
Y-228271D01*
X583824D01*
X584324Y-227771D01*
Y-225772D01*
X583824Y-225272D01*
X582325D01*
X587323Y-228271D02*
X585324D01*
X587323Y-226272D01*
Y-225772D01*
X586823Y-225272D01*
X585824D01*
X585324Y-225772D01*
X590322Y-228271D02*
X588323D01*
X590322Y-226272D01*
Y-225772D01*
X589822Y-225272D01*
X588823D01*
X588323Y-225772D01*
X583034Y-231571D02*
Y-234570D01*
X584533D01*
X585033Y-234070D01*
Y-232071D01*
X584533Y-231571D01*
X583034D01*
X588032Y-234570D02*
X586032D01*
X588032Y-232571D01*
Y-232071D01*
X587532Y-231571D01*
X586532D01*
X586032Y-232071D01*
X589032Y-234570D02*
X590031D01*
X589531D01*
Y-231571D01*
X589032Y-232071D01*
X395468Y-141133D02*
X392969D01*
X392469Y-141633D01*
Y-142633D01*
X392969Y-143132D01*
X395468D01*
X392469Y-144132D02*
Y-145132D01*
Y-144632D01*
X395468D01*
X394968Y-144132D01*
X392969Y-146631D02*
X392469Y-147131D01*
Y-148131D01*
X392969Y-148631D01*
X394968D01*
X395468Y-148131D01*
Y-147131D01*
X394968Y-146631D01*
X394468D01*
X393968Y-147131D01*
Y-148631D01*
X416724Y-129997D02*
Y-132496D01*
X417224Y-132996D01*
X418223D01*
X418723Y-132496D01*
Y-129997D01*
X419723Y-132996D02*
X420722D01*
X420223D01*
Y-129997D01*
X419723Y-130496D01*
X422222D02*
X422722Y-129997D01*
X423721D01*
X424221Y-130496D01*
Y-130996D01*
X423721Y-131496D01*
X424221Y-131996D01*
Y-132496D01*
X423721Y-132996D01*
X422722D01*
X422222Y-132496D01*
Y-131996D01*
X422722Y-131496D01*
X422222Y-130996D01*
Y-130496D01*
X422722Y-131496D02*
X423721D01*
X37984Y-36296D02*
Y-38795D01*
X38483Y-39295D01*
X39483D01*
X39983Y-38795D01*
Y-36296D01*
X40982Y-39295D02*
X41982D01*
X41482D01*
Y-36296D01*
X40982Y-36796D01*
X43482Y-36296D02*
X45481D01*
Y-36796D01*
X43482Y-38795D01*
Y-39295D01*
X342852Y-237720D02*
Y-234721D01*
X344351D01*
X344851Y-235221D01*
Y-236221D01*
X344351Y-236720D01*
X342852D01*
X343851D02*
X344851Y-237720D01*
X345851Y-234721D02*
X347850D01*
Y-235221D01*
X345851Y-237220D01*
Y-237720D01*
X350849Y-234721D02*
X349849Y-235221D01*
X348850Y-236221D01*
Y-237220D01*
X349350Y-237720D01*
X350349D01*
X350849Y-237220D01*
Y-236720D01*
X350349Y-236221D01*
X348850D01*
X319623Y-256618D02*
Y-253619D01*
X321123D01*
X321623Y-254118D01*
Y-255118D01*
X321123Y-255618D01*
X319623D01*
X320623D02*
X321623Y-256618D01*
X322622Y-253619D02*
X324622D01*
Y-254118D01*
X322622Y-256118D01*
Y-256618D01*
X327621Y-253619D02*
X325621D01*
Y-255118D01*
X326621Y-254618D01*
X327121D01*
X327621Y-255118D01*
Y-256118D01*
X327121Y-256618D01*
X326121D01*
X325621Y-256118D01*
X308993Y-230633D02*
Y-227634D01*
X310493D01*
X310993Y-228134D01*
Y-229134D01*
X310493Y-229634D01*
X308993D01*
X309993D02*
X310993Y-230633D01*
X311993Y-227634D02*
X313992D01*
Y-228134D01*
X311993Y-230134D01*
Y-230633D01*
X316491D02*
Y-227634D01*
X314991Y-229134D01*
X316991D01*
X177497Y-138507D02*
Y-135508D01*
X178997D01*
X179497Y-136008D01*
Y-137008D01*
X178997Y-137508D01*
X177497D01*
X178497D02*
X179497Y-138507D01*
X180496Y-135508D02*
X182496D01*
Y-136008D01*
X180496Y-138007D01*
Y-138507D01*
X183495Y-136008D02*
X183995Y-135508D01*
X184995D01*
X185495Y-136008D01*
Y-136508D01*
X184995Y-137008D01*
X184495D01*
X184995D01*
X185495Y-137508D01*
Y-138007D01*
X184995Y-138507D01*
X183995D01*
X183495Y-138007D01*
X376710Y-122759D02*
Y-119760D01*
X378209D01*
X378709Y-120260D01*
Y-121260D01*
X378209Y-121760D01*
X376710D01*
X377710D02*
X378709Y-122759D01*
X379709Y-119760D02*
X381708D01*
Y-120260D01*
X379709Y-122259D01*
Y-122759D01*
X384707D02*
X382708D01*
X384707Y-120760D01*
Y-120260D01*
X384208Y-119760D01*
X383208D01*
X382708Y-120260D01*
X178391Y-111342D02*
Y-108343D01*
X179890D01*
X180390Y-108843D01*
Y-109843D01*
X179890Y-110342D01*
X178391D01*
X179391D02*
X180390Y-111342D01*
X181390Y-108343D02*
X183389D01*
Y-108843D01*
X181390Y-110842D01*
Y-111342D01*
X184389D02*
X185389D01*
X184889D01*
Y-108343D01*
X184389Y-108843D01*
X392732Y-101544D02*
X393232Y-101044D01*
Y-100044D01*
X392732Y-99545D01*
X390733D01*
X390233Y-100044D01*
Y-101044D01*
X390733Y-101544D01*
X392732Y-102544D02*
X393232Y-103043D01*
Y-104043D01*
X392732Y-104543D01*
X392232D01*
X391732Y-104043D01*
X391232Y-104543D01*
X390733D01*
X390233Y-104043D01*
Y-103043D01*
X390733Y-102544D01*
X391232D01*
X391732Y-103043D01*
X392232Y-102544D01*
X392732D01*
X391732Y-103043D02*
Y-104043D01*
X392732Y-105543D02*
X393232Y-106043D01*
Y-107042D01*
X392732Y-107542D01*
X392232D01*
X391732Y-107042D01*
Y-106542D01*
Y-107042D01*
X391232Y-107542D01*
X390733D01*
X390233Y-107042D01*
Y-106043D01*
X390733Y-105543D01*
X344064Y-118685D02*
X343564Y-118185D01*
X342564D01*
X342064Y-118685D01*
Y-120685D01*
X342564Y-121185D01*
X343564D01*
X344064Y-120685D01*
X345063Y-118685D02*
X345563Y-118185D01*
X346563D01*
X347063Y-118685D01*
Y-119185D01*
X346563Y-119685D01*
X347063Y-120185D01*
Y-120685D01*
X346563Y-121185D01*
X345563D01*
X345063Y-120685D01*
Y-120185D01*
X345563Y-119685D01*
X345063Y-119185D01*
Y-118685D01*
X345563Y-119685D02*
X346563D01*
X350062Y-121185D02*
X348062D01*
X350062Y-119185D01*
Y-118685D01*
X349562Y-118185D01*
X348562D01*
X348062Y-118685D01*
X344170Y-112386D02*
X343670Y-111886D01*
X342670D01*
X342170Y-112386D01*
Y-114385D01*
X342670Y-114885D01*
X343670D01*
X344170Y-114385D01*
X345169Y-112386D02*
X345669Y-111886D01*
X346669D01*
X347169Y-112386D01*
Y-112886D01*
X346669Y-113386D01*
X347169Y-113886D01*
Y-114385D01*
X346669Y-114885D01*
X345669D01*
X345169Y-114385D01*
Y-113886D01*
X345669Y-113386D01*
X345169Y-112886D01*
Y-112386D01*
X345669Y-113386D02*
X346669D01*
X348168Y-114885D02*
X349168D01*
X348668D01*
Y-111886D01*
X348168Y-112386D01*
X382071Y-103968D02*
X381571Y-104468D01*
Y-105467D01*
X382071Y-105967D01*
X384070D01*
X384570Y-105467D01*
Y-104468D01*
X384070Y-103968D01*
X382071Y-102968D02*
X381571Y-102468D01*
Y-101469D01*
X382071Y-100969D01*
X382571D01*
X383071Y-101469D01*
X383571Y-100969D01*
X384070D01*
X384570Y-101469D01*
Y-102468D01*
X384070Y-102968D01*
X383571D01*
X383071Y-102468D01*
X382571Y-102968D01*
X382071D01*
X383071Y-102468D02*
Y-101469D01*
X382071Y-99969D02*
X381571Y-99469D01*
Y-98470D01*
X382071Y-97970D01*
X384070D01*
X384570Y-98470D01*
Y-99469D01*
X384070Y-99969D01*
X382071D01*
X334221Y-121048D02*
X333721Y-120548D01*
X332722D01*
X332222Y-121048D01*
Y-123047D01*
X332722Y-123547D01*
X333721D01*
X334221Y-123047D01*
X335221Y-120548D02*
X337220D01*
Y-121048D01*
X335221Y-123047D01*
Y-123547D01*
X338220Y-123047D02*
X338720Y-123547D01*
X339719D01*
X340219Y-123047D01*
Y-121048D01*
X339719Y-120548D01*
X338720D01*
X338220Y-121048D01*
Y-121547D01*
X338720Y-122047D01*
X340219D01*
X357056Y-106087D02*
X356556Y-105587D01*
X355556D01*
X355056Y-106087D01*
Y-108086D01*
X355556Y-108586D01*
X356556D01*
X357056Y-108086D01*
X358055Y-105587D02*
X360055D01*
Y-106087D01*
X358055Y-108086D01*
Y-108586D01*
X361054Y-106087D02*
X361554Y-105587D01*
X362554D01*
X363054Y-106087D01*
Y-106587D01*
X362554Y-107087D01*
X363054Y-107586D01*
Y-108086D01*
X362554Y-108586D01*
X361554D01*
X361054Y-108086D01*
Y-107586D01*
X361554Y-107087D01*
X361054Y-106587D01*
Y-106087D01*
X361554Y-107087D02*
X362554D01*
X461780Y-118292D02*
X461280Y-117792D01*
X460281D01*
X459781Y-118292D01*
Y-120291D01*
X460281Y-120791D01*
X461280D01*
X461780Y-120291D01*
X462780Y-117792D02*
X464779D01*
Y-118292D01*
X462780Y-120291D01*
Y-120791D01*
X465779Y-117792D02*
X467778D01*
Y-118292D01*
X465779Y-120291D01*
Y-120791D01*
X431958Y-118375D02*
X431459Y-118875D01*
Y-119874D01*
X431958Y-120374D01*
X433958D01*
X434458Y-119874D01*
Y-118875D01*
X433958Y-118375D01*
X431459Y-117375D02*
Y-115376D01*
X431958D01*
X433958Y-117375D01*
X434458D01*
X431459Y-112377D02*
X431958Y-113376D01*
X432958Y-114376D01*
X433958D01*
X434458Y-113876D01*
Y-112876D01*
X433958Y-112377D01*
X433458D01*
X432958Y-112876D01*
Y-114376D01*
X471472Y-102725D02*
X471972Y-102225D01*
Y-101225D01*
X471472Y-100726D01*
X469473D01*
X468973Y-101225D01*
Y-102225D01*
X469473Y-102725D01*
X471972Y-103725D02*
Y-105724D01*
X471472D01*
X469473Y-103725D01*
X468973D01*
X471972Y-108723D02*
Y-106724D01*
X470472D01*
X470972Y-107723D01*
Y-108223D01*
X470472Y-108723D01*
X469473D01*
X468973Y-108223D01*
Y-107224D01*
X469473Y-106724D01*
X188370Y-140188D02*
X187871Y-140688D01*
Y-141688D01*
X188370Y-142188D01*
X190370D01*
X190870Y-141688D01*
Y-140688D01*
X190370Y-140188D01*
X187871Y-137189D02*
X188370Y-138189D01*
X189370Y-139189D01*
X190370D01*
X190870Y-138689D01*
Y-137689D01*
X190370Y-137189D01*
X189870D01*
X189370Y-137689D01*
Y-139189D01*
X188370Y-136190D02*
X187871Y-135690D01*
Y-134690D01*
X188370Y-134190D01*
X188870D01*
X189370Y-134690D01*
X189870Y-134190D01*
X190370D01*
X190870Y-134690D01*
Y-135690D01*
X190370Y-136190D01*
X189870D01*
X189370Y-135690D01*
X188870Y-136190D01*
X188370D01*
X189370Y-135690D02*
Y-134690D01*
X154307Y-346638D02*
X153807Y-346138D01*
X152807D01*
X152307Y-346638D01*
Y-347138D01*
X152807Y-347638D01*
X153807D01*
X154307Y-348138D01*
Y-348638D01*
X153807Y-349137D01*
X152807D01*
X152307Y-348638D01*
X155306Y-346138D02*
Y-349137D01*
Y-348138D01*
X157306Y-346138D01*
X155806Y-347638D01*
X157306Y-349137D01*
X158305Y-346138D02*
X160305D01*
X159305D01*
Y-349137D01*
X161304D02*
X162304D01*
X161804D01*
Y-346138D01*
X161304Y-346638D01*
X163804D02*
X164303Y-346138D01*
X165303D01*
X165803Y-346638D01*
Y-348638D01*
X165303Y-349137D01*
X164303D01*
X163804Y-348638D01*
Y-346638D01*
X241777Y-323016D02*
X241277Y-322516D01*
X240277D01*
X239777Y-323016D01*
Y-323516D01*
X240277Y-324016D01*
X241277D01*
X241777Y-324516D01*
Y-325015D01*
X241277Y-325515D01*
X240277D01*
X239777Y-325015D01*
X242776Y-322516D02*
Y-325515D01*
Y-324516D01*
X244776Y-322516D01*
X243276Y-324016D01*
X244776Y-325515D01*
X245775Y-322516D02*
X247775D01*
X246775D01*
Y-325515D01*
X248775Y-325015D02*
X249274Y-325515D01*
X250274D01*
X250774Y-325015D01*
Y-323016D01*
X250274Y-322516D01*
X249274D01*
X248775Y-323016D01*
Y-323516D01*
X249274Y-324016D01*
X250774D01*
X173273Y-346638D02*
X172773Y-346138D01*
X171773D01*
X171273Y-346638D01*
Y-347138D01*
X171773Y-347638D01*
X172773D01*
X173273Y-348138D01*
Y-348638D01*
X172773Y-349137D01*
X171773D01*
X171273Y-348638D01*
X174273Y-346138D02*
Y-349137D01*
Y-348138D01*
X176272Y-346138D01*
X174772Y-347638D01*
X176272Y-349137D01*
X177271Y-346138D02*
X179271D01*
X178271D01*
Y-349137D01*
X180271Y-346638D02*
X180770Y-346138D01*
X181770D01*
X182270Y-346638D01*
Y-347138D01*
X181770Y-347638D01*
X182270Y-348138D01*
Y-348638D01*
X181770Y-349137D01*
X180770D01*
X180271Y-348638D01*
Y-348138D01*
X180770Y-347638D01*
X180271Y-347138D01*
Y-346638D01*
X180770Y-347638D02*
X181770D01*
X241777Y-173410D02*
X241277Y-172910D01*
X240277D01*
X239777Y-173410D01*
Y-173910D01*
X240277Y-174409D01*
X241277D01*
X241777Y-174909D01*
Y-175409D01*
X241277Y-175909D01*
X240277D01*
X239777Y-175409D01*
X242776Y-172910D02*
Y-175909D01*
Y-174909D01*
X244776Y-172910D01*
X243276Y-174409D01*
X244776Y-175909D01*
X245775Y-172910D02*
X247775D01*
X246775D01*
Y-175909D01*
X248775Y-172910D02*
X250774D01*
Y-173410D01*
X248775Y-175409D01*
Y-175909D01*
X26422Y-243095D02*
X25923Y-242595D01*
X24923D01*
X24423Y-243095D01*
Y-243595D01*
X24923Y-244094D01*
X25923D01*
X26422Y-244594D01*
Y-245094D01*
X25923Y-245594D01*
X24923D01*
X24423Y-245094D01*
X27422Y-242595D02*
Y-245594D01*
Y-244594D01*
X29421Y-242595D01*
X27922Y-244094D01*
X29421Y-245594D01*
X30421Y-242595D02*
X32420D01*
X31421D01*
Y-245594D01*
X35419Y-242595D02*
X34420Y-243095D01*
X33420Y-244094D01*
Y-245094D01*
X33920Y-245594D01*
X34920D01*
X35419Y-245094D01*
Y-244594D01*
X34920Y-244094D01*
X33420D01*
X55163Y-348607D02*
X54663Y-348107D01*
X53663D01*
X53163Y-348607D01*
Y-349107D01*
X53663Y-349606D01*
X54663D01*
X55163Y-350106D01*
Y-350606D01*
X54663Y-351106D01*
X53663D01*
X53163Y-350606D01*
X56162Y-348107D02*
Y-351106D01*
Y-350106D01*
X58162Y-348107D01*
X56662Y-349606D01*
X58162Y-351106D01*
X59161Y-348107D02*
X61161D01*
X60161D01*
Y-351106D01*
X64160Y-348107D02*
X62160D01*
Y-349606D01*
X63160Y-349107D01*
X63660D01*
X64160Y-349606D01*
Y-350606D01*
X63660Y-351106D01*
X62660D01*
X62160Y-350606D01*
X217367Y-346638D02*
X216867Y-346138D01*
X215868D01*
X215368Y-346638D01*
Y-347138D01*
X215868Y-347638D01*
X216867D01*
X217367Y-348138D01*
Y-348638D01*
X216867Y-349137D01*
X215868D01*
X215368Y-348638D01*
X218367Y-346138D02*
Y-349137D01*
Y-348138D01*
X220366Y-346138D01*
X218867Y-347638D01*
X220366Y-349137D01*
X221366Y-346138D02*
X223365D01*
X222366D01*
Y-349137D01*
X225865D02*
Y-346138D01*
X224365Y-347638D01*
X226364D01*
X202013Y-346638D02*
X201513Y-346138D01*
X200513D01*
X200014Y-346638D01*
Y-347138D01*
X200513Y-347638D01*
X201513D01*
X202013Y-348138D01*
Y-348638D01*
X201513Y-349137D01*
X200513D01*
X200014Y-348638D01*
X203013Y-346138D02*
Y-349137D01*
Y-348138D01*
X205012Y-346138D01*
X203513Y-347638D01*
X205012Y-349137D01*
X206012Y-346138D02*
X208011D01*
X207011D01*
Y-349137D01*
X209011Y-346638D02*
X209510Y-346138D01*
X210510D01*
X211010Y-346638D01*
Y-347138D01*
X210510Y-347638D01*
X210010D01*
X210510D01*
X211010Y-348138D01*
Y-348638D01*
X210510Y-349137D01*
X209510D01*
X209011Y-348638D01*
X27210Y-163567D02*
X26710Y-163067D01*
X25710D01*
X25210Y-163567D01*
Y-164067D01*
X25710Y-164567D01*
X26710D01*
X27210Y-165067D01*
Y-165567D01*
X26710Y-166066D01*
X25710D01*
X25210Y-165567D01*
X28209Y-163067D02*
Y-166066D01*
Y-165067D01*
X30209Y-163067D01*
X28709Y-164567D01*
X30209Y-166066D01*
X31209Y-163067D02*
X33208D01*
X32208D01*
Y-166066D01*
X36207D02*
X34207D01*
X36207Y-164067D01*
Y-163567D01*
X35707Y-163067D01*
X34707D01*
X34207Y-163567D01*
X187158Y-346638D02*
X186659Y-346138D01*
X185659D01*
X185159Y-346638D01*
Y-347138D01*
X185659Y-347638D01*
X186659D01*
X187158Y-348138D01*
Y-348638D01*
X186659Y-349137D01*
X185659D01*
X185159Y-348638D01*
X188158Y-346138D02*
Y-349137D01*
Y-348138D01*
X190157Y-346138D01*
X188658Y-347638D01*
X190157Y-349137D01*
X191157Y-346138D02*
X193157D01*
X192157D01*
Y-349137D01*
X194156D02*
X195156D01*
X194656D01*
Y-346138D01*
X194156Y-346638D01*
X291657Y-147354D02*
X288658D01*
Y-145854D01*
X289158Y-145354D01*
X290158D01*
X290657Y-145854D01*
Y-147354D01*
X291657Y-144355D02*
Y-143355D01*
Y-143855D01*
X288658D01*
X289158Y-144355D01*
X280844Y-153665D02*
Y-150666D01*
X282343D01*
X282843Y-151166D01*
Y-152165D01*
X282343Y-152665D01*
X280844D01*
X281843D02*
X282843Y-153665D01*
X285342D02*
Y-150666D01*
X283843Y-152165D01*
X285842D01*
X286842Y-150666D02*
X288841D01*
Y-151166D01*
X286842Y-153165D01*
Y-153665D01*
X565385Y21109D02*
X564386D01*
X564885D01*
Y18610D01*
X564386Y18110D01*
X563886D01*
X563386Y18610D01*
X566385Y20609D02*
X566885Y21109D01*
X567884D01*
X568384Y20609D01*
Y20110D01*
X567884Y19610D01*
X567384D01*
X567884D01*
X568384Y19110D01*
Y18610D01*
X567884Y18110D01*
X566885D01*
X566385Y18610D01*
X569384Y20609D02*
X569884Y21109D01*
X570883D01*
X571383Y20609D01*
Y20110D01*
X570883Y19610D01*
X571383Y19110D01*
Y18610D01*
X570883Y18110D01*
X569884D01*
X569384Y18610D01*
Y19110D01*
X569884Y19610D01*
X569384Y20110D01*
Y20609D01*
X569884Y19610D02*
X570883D01*
X281434Y-130240D02*
Y-127241D01*
X282934D01*
X283434Y-127741D01*
Y-128740D01*
X282934Y-129240D01*
X281434D01*
X282434D02*
X283434Y-130240D01*
X285933D02*
Y-127241D01*
X284433Y-128740D01*
X286433D01*
X289432Y-127241D02*
X288432Y-127741D01*
X287432Y-128740D01*
Y-129740D01*
X287932Y-130240D01*
X288932D01*
X289432Y-129740D01*
Y-129240D01*
X288932Y-128740D01*
X287432D01*
X281434Y-142444D02*
Y-139445D01*
X282934D01*
X283434Y-139945D01*
Y-140945D01*
X282934Y-141445D01*
X281434D01*
X282434D02*
X283434Y-142444D01*
X285933D02*
Y-139445D01*
X284433Y-140945D01*
X286433D01*
X289432Y-139445D02*
X287432D01*
Y-140945D01*
X288432Y-140445D01*
X288932D01*
X289432Y-140945D01*
Y-141945D01*
X288932Y-142444D01*
X287932D01*
X287432Y-141945D01*
X604012Y-30647D02*
X607011D01*
Y-32146D01*
X606511Y-32646D01*
X605512D01*
X605012Y-32146D01*
Y-30647D01*
Y-31647D02*
X604012Y-32646D01*
Y-35146D02*
X607011D01*
X605512Y-33646D01*
Y-35645D01*
X604012Y-38144D02*
X607011D01*
X605512Y-36645D01*
Y-38644D01*
X296504Y-334342D02*
Y-335342D01*
Y-334842D01*
X299003D01*
X299503Y-335342D01*
Y-335841D01*
X299003Y-336341D01*
X297004Y-333342D02*
X296504Y-332842D01*
Y-331843D01*
X297004Y-331343D01*
X297503D01*
X298003Y-331843D01*
Y-332343D01*
Y-331843D01*
X298503Y-331343D01*
X299003D01*
X299503Y-331843D01*
Y-332842D01*
X299003Y-333342D01*
X296504Y-330343D02*
Y-328344D01*
X297004D01*
X299003Y-330343D01*
X299503D01*
X251188Y-204406D02*
X250188D01*
X250688D01*
Y-206905D01*
X250188Y-207405D01*
X249688D01*
X249188Y-206905D01*
X252187Y-204906D02*
X252687Y-204406D01*
X253687D01*
X254187Y-204906D01*
Y-205406D01*
X253687Y-205906D01*
X253187D01*
X253687D01*
X254187Y-206405D01*
Y-206905D01*
X253687Y-207405D01*
X252687D01*
X252187Y-206905D01*
X257186Y-204406D02*
X256186Y-204906D01*
X255187Y-205906D01*
Y-206905D01*
X255686Y-207405D01*
X256686D01*
X257186Y-206905D01*
Y-206405D01*
X256686Y-205906D01*
X255187D01*
X405671Y-177317D02*
Y-176317D01*
Y-176817D01*
X403171D01*
X402671Y-176317D01*
Y-175818D01*
X403171Y-175318D01*
X405171Y-178317D02*
X405671Y-178817D01*
Y-179816D01*
X405171Y-180316D01*
X404671D01*
X404171Y-179816D01*
Y-179316D01*
Y-179816D01*
X403671Y-180316D01*
X403171D01*
X402671Y-179816D01*
Y-178817D01*
X403171Y-178317D01*
X405671Y-183315D02*
Y-181316D01*
X404171D01*
X404671Y-182315D01*
Y-182815D01*
X404171Y-183315D01*
X403171D01*
X402671Y-182815D01*
Y-181816D01*
X403171Y-181316D01*
X445405Y-306650D02*
X446405D01*
X445905D01*
Y-304151D01*
X446405Y-303651D01*
X446905D01*
X447404Y-304151D01*
X444406Y-306150D02*
X443906Y-306650D01*
X442906D01*
X442406Y-306150D01*
Y-305650D01*
X442906Y-305151D01*
X443406D01*
X442906D01*
X442406Y-304651D01*
Y-304151D01*
X442906Y-303651D01*
X443906D01*
X444406Y-304151D01*
X439907Y-303651D02*
Y-306650D01*
X441406Y-305151D01*
X439407D01*
X219285Y-271430D02*
X220285D01*
X219785D01*
Y-268931D01*
X220285Y-268431D01*
X220784D01*
X221284Y-268931D01*
X218285Y-270930D02*
X217785Y-271430D01*
X216786D01*
X216286Y-270930D01*
Y-270430D01*
X216786Y-269931D01*
X217285D01*
X216786D01*
X216286Y-269431D01*
Y-268931D01*
X216786Y-268431D01*
X217785D01*
X218285Y-268931D01*
X215286Y-268431D02*
X214286D01*
X214786D01*
Y-271430D01*
X215286Y-270930D01*
X571185Y-312818D02*
Y-311818D01*
Y-312318D01*
X568685D01*
X568186Y-311818D01*
Y-311318D01*
X568685Y-310818D01*
X568186Y-313817D02*
Y-314817D01*
Y-314317D01*
X571185D01*
X570685Y-313817D01*
Y-316316D02*
X571185Y-316816D01*
Y-317816D01*
X570685Y-318316D01*
X570185D01*
X569685Y-317816D01*
Y-317316D01*
Y-317816D01*
X569185Y-318316D01*
X568685D01*
X568186Y-317816D01*
Y-316816D01*
X568685Y-316316D01*
X139476Y-81814D02*
X140476D01*
X139976D01*
Y-79315D01*
X140476Y-78815D01*
X140976D01*
X141476Y-79315D01*
X136477Y-81814D02*
X137477Y-81315D01*
X138477Y-80315D01*
Y-79315D01*
X137977Y-78815D01*
X136977D01*
X136477Y-79315D01*
Y-79815D01*
X136977Y-80315D01*
X138477D01*
X583797Y-245200D02*
Y-242201D01*
X585296D01*
X585796Y-242701D01*
Y-243701D01*
X585296Y-244201D01*
X583797D01*
X584796D02*
X585796Y-245200D01*
X588295D02*
Y-242201D01*
X586796Y-243701D01*
X588795D01*
X589795Y-242701D02*
X590295Y-242201D01*
X591294D01*
X591794Y-242701D01*
Y-243201D01*
X591294Y-243701D01*
X590794D01*
X591294D01*
X591794Y-244201D01*
Y-244701D01*
X591294Y-245200D01*
X590295D01*
X589795Y-244701D01*
X608600Y-227090D02*
Y-224091D01*
X610099D01*
X610599Y-224591D01*
Y-225590D01*
X610099Y-226090D01*
X608600D01*
X609599D02*
X610599Y-227090D01*
X613098D02*
Y-224091D01*
X611599Y-225590D01*
X613598D01*
X616597Y-227090D02*
X614598D01*
X616597Y-225091D01*
Y-224591D01*
X616097Y-224091D01*
X615098D01*
X614598Y-224591D01*
X13968Y4992D02*
Y1993D01*
X15467D01*
X15967Y2493D01*
Y4492D01*
X15467Y4992D01*
X13968D01*
X16967Y1993D02*
X17966D01*
X17467D01*
Y4992D01*
X16967Y4492D01*
X19466D02*
X19966Y4992D01*
X20966D01*
X21465Y4492D01*
Y2493D01*
X20966Y1993D01*
X19966D01*
X19466Y2493D01*
Y4492D01*
X8918Y14885D02*
Y11886D01*
X10418D01*
X10917Y12386D01*
Y14386D01*
X10418Y14885D01*
X8918D01*
X11917Y12386D02*
X12417Y11886D01*
X13417D01*
X13916Y12386D01*
Y14386D01*
X13417Y14885D01*
X12417D01*
X11917Y14386D01*
Y13886D01*
X12417Y13386D01*
X13916D01*
X7343Y21578D02*
Y18579D01*
X8843D01*
X9343Y19079D01*
Y21078D01*
X8843Y21578D01*
X7343D01*
X10342Y21078D02*
X10842Y21578D01*
X11842D01*
X12342Y21078D01*
Y20579D01*
X11842Y20079D01*
X11342D01*
X11842D01*
X12342Y19579D01*
Y19079D01*
X11842Y18579D01*
X10842D01*
X10342Y19079D01*
X11999Y-332359D02*
Y-334858D01*
X12499Y-335358D01*
X13499D01*
X13999Y-334858D01*
Y-332359D01*
X14998Y-335358D02*
X15998D01*
X15498D01*
Y-332359D01*
X14998Y-332859D01*
X19497Y-332359D02*
X18497Y-332859D01*
X17497Y-333858D01*
Y-334858D01*
X17997Y-335358D01*
X18997D01*
X19497Y-334858D01*
Y-334358D01*
X18997Y-333858D01*
X17497D01*
X19873Y-223304D02*
Y-225803D01*
X20373Y-226303D01*
X21373D01*
X21873Y-225803D01*
Y-223304D01*
X22872Y-226303D02*
X23872D01*
X23372D01*
Y-223304D01*
X22872Y-223803D01*
X27371Y-226303D02*
X25372D01*
X27371Y-224303D01*
Y-223803D01*
X26871Y-223304D01*
X25871D01*
X25372Y-223803D01*
X17912Y-279603D02*
Y-282102D01*
X18412Y-282602D01*
X19412D01*
X19912Y-282102D01*
Y-279603D01*
X20911Y-282602D02*
X21911D01*
X21411D01*
Y-279603D01*
X20911Y-280103D01*
X23411Y-282602D02*
X24410D01*
X23911D01*
Y-279603D01*
X23411Y-280103D01*
X18367Y-175666D02*
Y-178165D01*
X18867Y-178665D01*
X19866D01*
X20366Y-178165D01*
Y-175666D01*
X21366Y-176166D02*
X21866Y-175666D01*
X22865D01*
X23365Y-176166D01*
Y-176665D01*
X22865Y-177165D01*
X23365Y-177665D01*
Y-178165D01*
X22865Y-178665D01*
X21866D01*
X21366Y-178165D01*
Y-177665D01*
X21866Y-177165D01*
X21366Y-176665D01*
Y-176166D01*
X21866Y-177165D02*
X22865D01*
X72640Y-107546D02*
Y-110045D01*
X73140Y-110545D01*
X74139D01*
X74639Y-110045D01*
Y-107546D01*
X77638D02*
X76638Y-108046D01*
X75639Y-109045D01*
Y-110045D01*
X76139Y-110545D01*
X77138D01*
X77638Y-110045D01*
Y-109545D01*
X77138Y-109045D01*
X75639D01*
X47034Y-135151D02*
Y-132152D01*
X48533D01*
X49033Y-132652D01*
Y-133652D01*
X48533Y-134151D01*
X47034D01*
X48033D02*
X49033Y-135151D01*
X51532D02*
Y-132152D01*
X50033Y-133652D01*
X52032D01*
X53032Y-135151D02*
X54031D01*
X53532D01*
Y-132152D01*
X53032Y-132652D01*
X65555Y-112467D02*
Y-115466D01*
X64055D01*
X63556Y-114966D01*
Y-113967D01*
X64055Y-113467D01*
X65555D01*
X64555D02*
X63556Y-112467D01*
X61056D02*
Y-115466D01*
X62556Y-113967D01*
X60557D01*
X59557Y-114966D02*
X59057Y-115466D01*
X58057D01*
X57557Y-114966D01*
Y-112967D01*
X58057Y-112467D01*
X59057D01*
X59557Y-112967D01*
Y-114966D01*
X-4012Y-342581D02*
X-7011D01*
Y-341082D01*
X-6511Y-340582D01*
X-5512D01*
X-5012Y-341082D01*
Y-342581D01*
Y-341582D02*
X-4012Y-340582D01*
X-6511Y-339582D02*
X-7011Y-339083D01*
Y-338083D01*
X-6511Y-337583D01*
X-6012D01*
X-5512Y-338083D01*
Y-338583D01*
Y-338083D01*
X-5012Y-337583D01*
X-4512D01*
X-4012Y-338083D01*
Y-339083D01*
X-4512Y-339582D01*
X-4012Y-335084D02*
X-7011D01*
X-5512Y-336583D01*
Y-334584D01*
X14248Y-219623D02*
X17248D01*
Y-221123D01*
X16748Y-221623D01*
X15748D01*
X15248Y-221123D01*
Y-219623D01*
Y-220623D02*
X14248Y-221623D01*
X16748Y-222622D02*
X17248Y-223122D01*
Y-224122D01*
X16748Y-224622D01*
X16248D01*
X15748Y-224122D01*
Y-223622D01*
Y-224122D01*
X15248Y-224622D01*
X14748D01*
X14248Y-224122D01*
Y-223122D01*
X14748Y-222622D01*
X16748Y-225621D02*
X17248Y-226121D01*
Y-227121D01*
X16748Y-227621D01*
X16248D01*
X15748Y-227121D01*
Y-226621D01*
Y-227121D01*
X15248Y-227621D01*
X14748D01*
X14248Y-227121D01*
Y-226121D01*
X14748Y-225621D01*
X-4406Y-353211D02*
X-7405D01*
Y-351712D01*
X-6905Y-351212D01*
X-5906D01*
X-5406Y-351712D01*
Y-353211D01*
Y-352212D02*
X-4406Y-351212D01*
X-6905Y-350212D02*
X-7405Y-349712D01*
Y-348713D01*
X-6905Y-348213D01*
X-6405D01*
X-5906Y-348713D01*
Y-349213D01*
Y-348713D01*
X-5406Y-348213D01*
X-4906D01*
X-4406Y-348713D01*
Y-349712D01*
X-4906Y-350212D01*
X-4406Y-345214D02*
Y-347213D01*
X-6405Y-345214D01*
X-6905D01*
X-7405Y-345714D01*
Y-346713D01*
X-6905Y-347213D01*
X24365Y-353619D02*
Y-356618D01*
X22865D01*
X22366Y-356118D01*
Y-355118D01*
X22865Y-354618D01*
X24365D01*
X23365D02*
X22366Y-353619D01*
X21366Y-356118D02*
X20866Y-356618D01*
X19866D01*
X19367Y-356118D01*
Y-355618D01*
X19866Y-355118D01*
X20366D01*
X19866D01*
X19367Y-354618D01*
Y-354118D01*
X19866Y-353619D01*
X20866D01*
X21366Y-354118D01*
X18367Y-353619D02*
X17367D01*
X17867D01*
Y-356618D01*
X18367Y-356118D01*
X603468Y-121397D02*
X600469D01*
Y-119897D01*
X600969Y-119397D01*
X601968D01*
X602468Y-119897D01*
Y-121397D01*
X600969Y-118398D02*
X600469Y-117898D01*
Y-116898D01*
X600969Y-116399D01*
X601469D01*
X601968Y-116898D01*
Y-117398D01*
Y-116898D01*
X602468Y-116399D01*
X602968D01*
X603468Y-116898D01*
Y-117898D01*
X602968Y-118398D01*
X23516Y-304012D02*
X22516D01*
X23016D01*
Y-306511D01*
X22516Y-307011D01*
X22016D01*
X21517Y-306511D01*
X26015Y-307011D02*
Y-304012D01*
X24516Y-305512D01*
X26515D01*
X16823Y-198107D02*
X15823D01*
X16323D01*
Y-200606D01*
X15823Y-201106D01*
X15324D01*
X14824Y-200606D01*
X19822Y-201106D02*
X17823D01*
X19822Y-199107D01*
Y-198607D01*
X19322Y-198107D01*
X18323D01*
X17823Y-198607D01*
X17610Y-248894D02*
X16611D01*
X17111D01*
Y-251393D01*
X16611Y-251893D01*
X16111D01*
X15611Y-251393D01*
X18610Y-249394D02*
X19110Y-248894D01*
X20110D01*
X20609Y-249394D01*
Y-249894D01*
X20110Y-250394D01*
X19610D01*
X20110D01*
X20609Y-250893D01*
Y-251393D01*
X20110Y-251893D01*
X19110D01*
X18610Y-251393D01*
X19291Y-142201D02*
X18292D01*
X18791D01*
Y-144701D01*
X18292Y-145200D01*
X17792D01*
X17292Y-144701D01*
X20291Y-145200D02*
X21291D01*
X20791D01*
Y-142201D01*
X20291Y-142701D01*
X-11099Y-337983D02*
X-14098D01*
Y-339483D01*
X-13598Y-339983D01*
X-11599D01*
X-11099Y-339483D01*
Y-337983D01*
X-14098Y-340983D02*
Y-341982D01*
Y-341482D01*
X-11099D01*
X-11599Y-340983D01*
Y-343482D02*
X-11099Y-343982D01*
Y-344981D01*
X-11599Y-345481D01*
X-12099D01*
X-12598Y-344981D01*
X-13098Y-345481D01*
X-13598D01*
X-14098Y-344981D01*
Y-343982D01*
X-13598Y-343482D01*
X-13098D01*
X-12598Y-343982D01*
X-12099Y-343482D01*
X-11599D01*
X-12598Y-343982D02*
Y-344981D01*
X-11099Y-285228D02*
X-14098D01*
Y-286727D01*
X-13598Y-287227D01*
X-11599D01*
X-11099Y-286727D01*
Y-285228D01*
X-14098Y-288227D02*
Y-289226D01*
Y-288726D01*
X-11099D01*
X-11599Y-288227D01*
X-11099Y-290726D02*
Y-292725D01*
X-11599D01*
X-13598Y-290726D01*
X-14098D01*
X-11099Y-232078D02*
X-14098D01*
Y-233577D01*
X-13598Y-234077D01*
X-11599D01*
X-11099Y-233577D01*
Y-232078D01*
X-14098Y-235077D02*
Y-236077D01*
Y-235577D01*
X-11099D01*
X-11599Y-235077D01*
X-11099Y-239576D02*
X-11599Y-238576D01*
X-12598Y-237576D01*
X-13598D01*
X-14098Y-238076D01*
Y-239076D01*
X-13598Y-239576D01*
X-13098D01*
X-12598Y-239076D01*
Y-237576D01*
X-11886Y-180897D02*
X-14885D01*
Y-182396D01*
X-14386Y-182896D01*
X-12386D01*
X-11886Y-182396D01*
Y-180897D01*
X-14885Y-183896D02*
Y-184896D01*
Y-184396D01*
X-11886D01*
X-12386Y-183896D01*
X-11886Y-188394D02*
Y-186395D01*
X-13386D01*
X-12886Y-187395D01*
Y-187895D01*
X-13386Y-188394D01*
X-14386D01*
X-14885Y-187895D01*
Y-186895D01*
X-14386Y-186395D01*
X49139Y-124824D02*
X48639Y-125324D01*
Y-126324D01*
X49139Y-126823D01*
X51139D01*
X51638Y-126324D01*
Y-125324D01*
X51139Y-124824D01*
X51638Y-122325D02*
X48639D01*
X50139Y-123825D01*
Y-121825D01*
X49139Y-120826D02*
X48639Y-120326D01*
Y-119326D01*
X49139Y-118826D01*
X51139D01*
X51638Y-119326D01*
Y-120326D01*
X51139Y-120826D01*
X49139D01*
X44612Y-124824D02*
X44112Y-125324D01*
Y-126324D01*
X44612Y-126823D01*
X46611D01*
X47111Y-126324D01*
Y-125324D01*
X46611Y-124824D01*
X44612Y-123825D02*
X44112Y-123325D01*
Y-122325D01*
X44612Y-121825D01*
X45111D01*
X45611Y-122325D01*
Y-122825D01*
Y-122325D01*
X46111Y-121825D01*
X46611D01*
X47111Y-122325D01*
Y-123325D01*
X46611Y-123825D01*
X44612Y-120826D02*
X44112Y-120326D01*
Y-119326D01*
X44612Y-118826D01*
X45111D01*
X45611Y-119326D01*
X46111Y-118826D01*
X46611D01*
X47111Y-119326D01*
Y-120326D01*
X46611Y-120826D01*
X46111D01*
X45611Y-120326D01*
X45111Y-120826D01*
X44612D01*
X45611Y-120326D02*
Y-119326D01*
X153756Y-90914D02*
X154255Y-90414D01*
Y-89415D01*
X153756Y-88915D01*
X151756D01*
X151256Y-89415D01*
Y-90414D01*
X151756Y-90914D01*
X153756Y-91914D02*
X154255Y-92414D01*
Y-93413D01*
X153756Y-93913D01*
X153256D01*
X152756Y-93413D01*
Y-92913D01*
Y-93413D01*
X152256Y-93913D01*
X151756D01*
X151256Y-93413D01*
Y-92414D01*
X151756Y-91914D01*
X151256Y-96912D02*
Y-94913D01*
X153256Y-96912D01*
X153756D01*
X154255Y-96412D01*
Y-95413D01*
X153756Y-94913D01*
X518692Y-74878D02*
Y-77378D01*
X519192Y-77877D01*
X520192D01*
X520691Y-77378D01*
Y-74878D01*
X521691Y-77877D02*
X522691D01*
X522191D01*
Y-74878D01*
X521691Y-75378D01*
X526190Y-74878D02*
X524190D01*
Y-76378D01*
X525190Y-75878D01*
X525690D01*
X526190Y-76378D01*
Y-77378D01*
X525690Y-77877D01*
X524690D01*
X524190Y-77378D01*
X9767Y-285296D02*
X6768D01*
Y-286796D01*
X7268Y-287295D01*
X9267D01*
X9767Y-286796D01*
Y-285296D01*
X6768Y-290295D02*
Y-288295D01*
X8767Y-290295D01*
X9267D01*
X9767Y-289795D01*
Y-288795D01*
X9267Y-288295D01*
X10322Y-182230D02*
X7323D01*
Y-183729D01*
X7823Y-184229D01*
X9823D01*
X10322Y-183729D01*
Y-182230D01*
X7323Y-185229D02*
Y-186229D01*
Y-185729D01*
X10322D01*
X9823Y-185229D01*
X225385Y-138658D02*
Y-141157D01*
X225885Y-141657D01*
X226885D01*
X227384Y-141157D01*
Y-138658D01*
X228384Y-141657D02*
X229384D01*
X228884D01*
Y-138658D01*
X228384Y-139158D01*
X230883D02*
X231383Y-138658D01*
X232383D01*
X232883Y-139158D01*
Y-141157D01*
X232383Y-141657D01*
X231383D01*
X230883Y-141157D01*
Y-139158D01*
X22629Y-197956D02*
Y-194957D01*
X24129D01*
X24629Y-195457D01*
Y-196457D01*
X24129Y-196957D01*
X22629D01*
X23629D02*
X24629Y-197956D01*
X25628D02*
X26628D01*
X26128D01*
Y-194957D01*
X25628Y-195457D01*
X29627Y-197956D02*
Y-194957D01*
X28127Y-196457D01*
X30127D01*
X132812Y-138117D02*
Y-135618D01*
X132312Y-135118D01*
X131313D01*
X130813Y-135618D01*
Y-138117D01*
X129813Y-135118D02*
X128813D01*
X129313D01*
Y-138117D01*
X129813Y-137617D01*
X125814Y-135118D02*
Y-138117D01*
X127314Y-136618D01*
X125315D01*
X147319Y-138394D02*
X149819D01*
X150318Y-137895D01*
Y-136895D01*
X149819Y-136395D01*
X147319D01*
X150318Y-135395D02*
Y-134396D01*
Y-134896D01*
X147319D01*
X147819Y-135395D01*
Y-132896D02*
X147319Y-132396D01*
Y-131397D01*
X147819Y-130897D01*
X148319D01*
X148819Y-131397D01*
Y-131897D01*
Y-131397D01*
X149319Y-130897D01*
X149819D01*
X150318Y-131397D01*
Y-132396D01*
X149819Y-132896D01*
X192349Y-121397D02*
X194849D01*
X195348Y-120897D01*
Y-119897D01*
X194849Y-119397D01*
X192349D01*
X195348Y-116898D02*
X192349D01*
X193849Y-118398D01*
Y-116399D01*
X217792Y-116672D02*
X220291D01*
X220791Y-116173D01*
Y-115173D01*
X220291Y-114673D01*
X217792D01*
X218292Y-113673D02*
X217792Y-113173D01*
Y-112174D01*
X218292Y-111674D01*
X218792D01*
X219291Y-112174D01*
Y-112674D01*
Y-112174D01*
X219791Y-111674D01*
X220291D01*
X220791Y-112174D01*
Y-113173D01*
X220291Y-113673D01*
X8993Y-172169D02*
Y-169170D01*
X10493D01*
X10993Y-169670D01*
Y-170669D01*
X10493Y-171169D01*
X8993D01*
X9993D02*
X10993Y-172169D01*
X13992D02*
X11992D01*
X13992Y-170169D01*
Y-169670D01*
X13492Y-169170D01*
X12492D01*
X11992Y-169670D01*
X16991Y-169170D02*
X14991D01*
Y-170669D01*
X15991Y-170169D01*
X16491D01*
X16991Y-170669D01*
Y-171669D01*
X16491Y-172169D01*
X15491D01*
X14991Y-171669D01*
X619086Y-226303D02*
Y-223304D01*
X620585D01*
X621085Y-223803D01*
Y-224803D01*
X620585Y-225303D01*
X619086D01*
X620085D02*
X621085Y-226303D01*
X622085D02*
X623085D01*
X622585D01*
Y-223304D01*
X622085Y-223803D01*
X624584D02*
X625084Y-223304D01*
X626084D01*
X626583Y-223803D01*
Y-224303D01*
X626084Y-224803D01*
X625584D01*
X626084D01*
X626583Y-225303D01*
Y-225803D01*
X626084Y-226303D01*
X625084D01*
X624584Y-225803D01*
X144053Y-111462D02*
X144553Y-111962D01*
X145553D01*
X146053Y-111462D01*
Y-109463D01*
X145553Y-108963D01*
X144553D01*
X144053Y-109463D01*
X143054Y-111462D02*
X142554Y-111962D01*
X141554D01*
X141054Y-111462D01*
Y-110962D01*
X141554Y-110462D01*
X142054D01*
X141554D01*
X141054Y-109963D01*
Y-109463D01*
X141554Y-108963D01*
X142554D01*
X143054Y-109463D01*
X140055Y-108963D02*
X139055D01*
X139555D01*
Y-111962D01*
X140055Y-111462D01*
X131900Y-126054D02*
X132400Y-126553D01*
X133399D01*
X133899Y-126054D01*
Y-124054D01*
X133399Y-123554D01*
X132400D01*
X131900Y-124054D01*
X130900Y-126054D02*
X130400Y-126553D01*
X129401D01*
X128901Y-126054D01*
Y-125554D01*
X129401Y-125054D01*
X129901D01*
X129401D01*
X128901Y-124554D01*
Y-124054D01*
X129401Y-123554D01*
X130400D01*
X130900Y-124054D01*
X127901Y-126054D02*
X127401Y-126553D01*
X126402D01*
X125902Y-126054D01*
Y-124054D01*
X126402Y-123554D01*
X127401D01*
X127901Y-124054D01*
Y-126054D01*
X-1606Y-237977D02*
X-2105Y-237477D01*
X-3105D01*
X-3605Y-237977D01*
Y-239976D01*
X-3105Y-240476D01*
X-2105D01*
X-1606Y-239976D01*
X1393Y-240476D02*
X-606D01*
X1393Y-238476D01*
Y-237977D01*
X893Y-237477D01*
X-106D01*
X-606Y-237977D01*
X2393Y-239976D02*
X2893Y-240476D01*
X3893D01*
X4392Y-239976D01*
Y-237977D01*
X3893Y-237477D01*
X2893D01*
X2393Y-237977D01*
Y-238476D01*
X2893Y-238976D01*
X4392D01*
X9086Y-356118D02*
X9586Y-356618D01*
X10586D01*
X11085Y-356118D01*
Y-354118D01*
X10586Y-353619D01*
X9586D01*
X9086Y-354118D01*
X6087Y-353619D02*
X8086D01*
X6087Y-355618D01*
Y-356118D01*
X6587Y-356618D01*
X7586D01*
X8086Y-356118D01*
X5087D02*
X4587Y-356618D01*
X3588D01*
X3088Y-356118D01*
Y-355618D01*
X3588Y-355118D01*
X3088Y-354618D01*
Y-354118D01*
X3588Y-353619D01*
X4587D01*
X5087Y-354118D01*
Y-354618D01*
X4587Y-355118D01*
X5087Y-355618D01*
Y-356118D01*
X4587Y-355118D02*
X3588D01*
X20685Y-297213D02*
X21185Y-296713D01*
Y-295714D01*
X20685Y-295214D01*
X18685D01*
X18185Y-295714D01*
Y-296713D01*
X18685Y-297213D01*
X18185Y-300212D02*
Y-298213D01*
X20185Y-300212D01*
X20685D01*
X21185Y-299712D01*
Y-298713D01*
X20685Y-298213D01*
X21185Y-301212D02*
Y-303211D01*
X20685D01*
X18685Y-301212D01*
X18185D01*
X-818Y-192307D02*
X-1318Y-191808D01*
X-2318D01*
X-2818Y-192307D01*
Y-194307D01*
X-2318Y-194807D01*
X-1318D01*
X-818Y-194307D01*
X2181Y-194807D02*
X181D01*
X2181Y-192807D01*
Y-192307D01*
X1681Y-191808D01*
X681D01*
X181Y-192307D01*
X5180Y-191808D02*
X4180Y-192307D01*
X3181Y-193307D01*
Y-194307D01*
X3680Y-194807D01*
X4680D01*
X5180Y-194307D01*
Y-193807D01*
X4680Y-193307D01*
X3181D01*
X-11811Y-141339D02*
Y-139339D01*
X-10811Y-138340D01*
X-9812Y-139339D01*
Y-141339D01*
Y-139839D01*
X-11811D01*
X-8812Y-141339D02*
Y-138340D01*
X-6813Y-141339D01*
Y-138340D01*
X-5813Y-141339D02*
X-4813D01*
X-5313D01*
Y-138340D01*
X-5813Y-138839D01*
X-11811Y-248031D02*
Y-246032D01*
X-10811Y-245033D01*
X-9812Y-246032D01*
Y-248031D01*
Y-246532D01*
X-11811D01*
X-8812Y-248031D02*
Y-245033D01*
X-6813Y-248031D01*
Y-245033D01*
X-5813Y-245532D02*
X-5313Y-245033D01*
X-4313D01*
X-3814Y-245532D01*
Y-246032D01*
X-4313Y-246532D01*
X-4813D01*
X-4313D01*
X-3814Y-247032D01*
Y-247532D01*
X-4313Y-248031D01*
X-5313D01*
X-5813Y-247532D01*
X-15354Y-195276D02*
Y-193276D01*
X-14355Y-192277D01*
X-13355Y-193276D01*
Y-195276D01*
Y-193776D01*
X-15354D01*
X-12355Y-195276D02*
Y-192277D01*
X-10356Y-195276D01*
Y-192277D01*
X-7357Y-195276D02*
X-9356D01*
X-7357Y-193276D01*
Y-192776D01*
X-7857Y-192277D01*
X-8856D01*
X-9356Y-192776D01*
X-12205Y-301969D02*
Y-299969D01*
X-11205Y-298970D01*
X-10205Y-299969D01*
Y-301969D01*
Y-300469D01*
X-12205D01*
X-9206Y-301969D02*
Y-298970D01*
X-7206Y-301969D01*
Y-298970D01*
X-4707Y-301969D02*
Y-298970D01*
X-6207Y-300469D01*
X-4207D01*
X425801Y-184475D02*
Y-186975D01*
X426301Y-187474D01*
X427301D01*
X427800Y-186975D01*
Y-184475D01*
X428800D02*
X430799D01*
Y-184975D01*
X428800Y-186975D01*
Y-187474D01*
X133071Y-81739D02*
Y-79240D01*
X132571Y-78740D01*
X131571D01*
X131071Y-79240D01*
Y-81739D01*
X130072Y-79240D02*
X129572Y-78740D01*
X128572D01*
X128073Y-79240D01*
Y-81239D01*
X128572Y-81739D01*
X129572D01*
X130072Y-81239D01*
Y-80739D01*
X129572Y-80240D01*
X128073D01*
X60236Y-37645D02*
Y-35146D01*
X59736Y-34646D01*
X58737D01*
X58237Y-35146D01*
Y-37645D01*
X55238D02*
X57237D01*
Y-36145D01*
X56238Y-36645D01*
X55738D01*
X55238Y-36145D01*
Y-35146D01*
X55738Y-34646D01*
X56737D01*
X57237Y-35146D01*
X620322Y-70866D02*
X617823D01*
X617323Y-71366D01*
Y-72366D01*
X617823Y-72865D01*
X620322D01*
X617323Y-75864D02*
Y-73865D01*
X619322Y-75864D01*
X619822D01*
X620322Y-75365D01*
Y-74365D01*
X619822Y-73865D01*
X1181Y-230709D02*
Y-227710D01*
X2681D01*
X3181Y-228209D01*
Y-229209D01*
X2681Y-229709D01*
X1181D01*
X2181D02*
X3181Y-230709D01*
X4180Y-228209D02*
X4680Y-227710D01*
X5680D01*
X6179Y-228209D01*
Y-228709D01*
X5680Y-229209D01*
X5180D01*
X5680D01*
X6179Y-229709D01*
Y-230209D01*
X5680Y-230709D01*
X4680D01*
X4180Y-230209D01*
X7179Y-228209D02*
X7679Y-227710D01*
X8679D01*
X9178Y-228209D01*
Y-230209D01*
X8679Y-230709D01*
X7679D01*
X7179Y-230209D01*
Y-228209D01*
X15354Y-245276D02*
Y-242277D01*
X16854D01*
X17354Y-242776D01*
Y-243776D01*
X16854Y-244276D01*
X15354D01*
X16354D02*
X17354Y-245276D01*
X20353D02*
X18353D01*
X20353Y-243276D01*
Y-242776D01*
X19853Y-242277D01*
X18853D01*
X18353Y-242776D01*
X21352Y-244776D02*
X21852Y-245276D01*
X22852D01*
X23352Y-244776D01*
Y-242776D01*
X22852Y-242277D01*
X21852D01*
X21352Y-242776D01*
Y-243276D01*
X21852Y-243776D01*
X23352D01*
X9055Y-276586D02*
Y-273587D01*
X10555D01*
X11055Y-274087D01*
Y-275087D01*
X10555Y-275586D01*
X9055D01*
X10055D02*
X11055Y-276586D01*
X14053D02*
X12054D01*
X14053Y-274587D01*
Y-274087D01*
X13554Y-273587D01*
X12554D01*
X12054Y-274087D01*
X15053D02*
X15553Y-273587D01*
X16553D01*
X17052Y-274087D01*
Y-274587D01*
X16553Y-275087D01*
X17052Y-275586D01*
Y-276086D01*
X16553Y-276586D01*
X15553D01*
X15053Y-276086D01*
Y-275586D01*
X15553Y-275087D01*
X15053Y-274587D01*
Y-274087D01*
X15553Y-275087D02*
X16553D01*
X119685Y-354724D02*
Y-351725D01*
X121185D01*
X121684Y-352225D01*
Y-353225D01*
X121185Y-353725D01*
X119685D01*
X120685D02*
X121684Y-354724D01*
X124683D02*
X122684D01*
X124683Y-352725D01*
Y-352225D01*
X124184Y-351725D01*
X123184D01*
X122684Y-352225D01*
X127183Y-354724D02*
Y-351725D01*
X125683Y-353225D01*
X127682D01*
X119685Y-349606D02*
Y-346607D01*
X121185D01*
X121684Y-347107D01*
Y-348107D01*
X121185Y-348607D01*
X119685D01*
X120685D02*
X121684Y-349606D01*
X124683D02*
X122684D01*
X124683Y-347607D01*
Y-347107D01*
X124184Y-346607D01*
X123184D01*
X122684Y-347107D01*
X125683D02*
X126183Y-346607D01*
X127183D01*
X127682Y-347107D01*
Y-347607D01*
X127183Y-348107D01*
X126683D01*
X127183D01*
X127682Y-348607D01*
Y-349107D01*
X127183Y-349606D01*
X126183D01*
X125683Y-349107D01*
X520354Y-350391D02*
Y-347392D01*
X521854D01*
X522354Y-347892D01*
Y-348891D01*
X521854Y-349391D01*
X520354D01*
X521354D02*
X522354Y-350391D01*
X525353D02*
X523353D01*
X525353Y-348391D01*
Y-347892D01*
X524853Y-347392D01*
X523853D01*
X523353Y-347892D01*
X526352Y-350391D02*
X527352D01*
X526852D01*
Y-347392D01*
X526352Y-347892D01*
X565039Y-350391D02*
Y-347392D01*
X566539D01*
X567039Y-347892D01*
Y-348891D01*
X566539Y-349391D01*
X565039D01*
X566039D02*
X567039Y-350391D01*
X570038D02*
X568038D01*
X570038Y-348391D01*
Y-347892D01*
X569538Y-347392D01*
X568538D01*
X568038Y-347892D01*
X571037D02*
X571537Y-347392D01*
X572537D01*
X573037Y-347892D01*
Y-349891D01*
X572537Y-350391D01*
X571537D01*
X571037Y-349891D01*
Y-347892D01*
X480318Y-351260D02*
Y-348261D01*
X481817D01*
X482317Y-348761D01*
Y-349760D01*
X481817Y-350260D01*
X480318D01*
X481318D02*
X482317Y-351260D01*
X483317D02*
X484317D01*
X483817D01*
Y-348261D01*
X483317Y-348761D01*
X485816Y-350760D02*
X486316Y-351260D01*
X487316D01*
X487816Y-350760D01*
Y-348761D01*
X487316Y-348261D01*
X486316D01*
X485816Y-348761D01*
Y-349260D01*
X486316Y-349760D01*
X487816D01*
X438192Y-351260D02*
Y-348261D01*
X439691D01*
X440191Y-348761D01*
Y-349760D01*
X439691Y-350260D01*
X438192D01*
X439192D02*
X440191Y-351260D01*
X441191D02*
X442191D01*
X441691D01*
Y-348261D01*
X441191Y-348761D01*
X443690D02*
X444190Y-348261D01*
X445190D01*
X445689Y-348761D01*
Y-349260D01*
X445190Y-349760D01*
X445689Y-350260D01*
Y-350760D01*
X445190Y-351260D01*
X444190D01*
X443690Y-350760D01*
Y-350260D01*
X444190Y-349760D01*
X443690Y-349260D01*
Y-348761D01*
X444190Y-349760D02*
X445190D01*
X80709Y-35039D02*
Y-32040D01*
X82208D01*
X82708Y-32540D01*
Y-33540D01*
X82208Y-34040D01*
X80709D01*
X81708D02*
X82708Y-35039D01*
X83708Y-32540D02*
X84207Y-32040D01*
X85207D01*
X85707Y-32540D01*
Y-33040D01*
X85207Y-33540D01*
X85707Y-34040D01*
Y-34539D01*
X85207Y-35039D01*
X84207D01*
X83708Y-34539D01*
Y-34040D01*
X84207Y-33540D01*
X83708Y-33040D01*
Y-32540D01*
X84207Y-33540D02*
X85207D01*
X604724Y-53937D02*
Y-50938D01*
X606224D01*
X606724Y-51438D01*
Y-52438D01*
X606224Y-52937D01*
X604724D01*
X605724D02*
X606724Y-53937D01*
X607723Y-50938D02*
X609723D01*
Y-51438D01*
X607723Y-53437D01*
Y-53937D01*
X83071Y-101181D02*
Y-98182D01*
X84570D01*
X85070Y-98682D01*
Y-99682D01*
X84570Y-100181D01*
X83071D01*
X84071D02*
X85070Y-101181D01*
X86070D02*
X87070D01*
X86570D01*
Y-98182D01*
X86070Y-98682D01*
X584403Y-38552D02*
Y-40551D01*
X585902D01*
Y-39551D01*
Y-40551D01*
X587402D01*
Y-37552D02*
Y-36553D01*
Y-37052D01*
X584403D01*
X584902Y-37552D01*
X-22684Y-126969D02*
X-19685D01*
Y-125469D01*
X-20185Y-124969D01*
X-22184D01*
X-22684Y-125469D01*
Y-126969D01*
X-19685Y-123969D02*
Y-122970D01*
Y-123470D01*
X-22684D01*
X-22184Y-123969D01*
X-19685Y-119971D02*
X-22684D01*
X-21185Y-121470D01*
Y-119471D01*
X-22684Y-83661D02*
X-19685D01*
Y-82162D01*
X-20185Y-81662D01*
X-22184D01*
X-22684Y-82162D01*
Y-83661D01*
X-19685Y-80662D02*
Y-79663D01*
Y-80163D01*
X-22684D01*
X-22184Y-80662D01*
Y-78163D02*
X-22684Y-77663D01*
Y-76664D01*
X-22184Y-76164D01*
X-21684D01*
X-21185Y-76664D01*
Y-77163D01*
Y-76664D01*
X-20685Y-76164D01*
X-20185D01*
X-19685Y-76664D01*
Y-77663D01*
X-20185Y-78163D01*
X14173Y-3300D02*
Y-6299D01*
X15673D01*
X16173Y-5799D01*
Y-3800D01*
X15673Y-3300D01*
X14173D01*
X17172Y-6299D02*
X18172D01*
X17672D01*
Y-3300D01*
X17172Y-3800D01*
X19671Y-6299D02*
X20671D01*
X20171D01*
Y-3300D01*
X19671Y-3800D01*
X506299Y-346607D02*
Y-349606D01*
X507799D01*
X508299Y-349107D01*
Y-347107D01*
X507799Y-346607D01*
X506299D01*
X509298Y-347107D02*
X509798Y-346607D01*
X510798D01*
X511298Y-347107D01*
Y-347607D01*
X510798Y-348107D01*
X511298Y-348607D01*
Y-349107D01*
X510798Y-349606D01*
X509798D01*
X509298Y-349107D01*
Y-348607D01*
X509798Y-348107D01*
X509298Y-347607D01*
Y-347107D01*
X509798Y-348107D02*
X510798D01*
X550787Y-347395D02*
Y-350394D01*
X552287D01*
X552787Y-349894D01*
Y-347895D01*
X552287Y-347395D01*
X550787D01*
X553786D02*
X555786D01*
Y-347895D01*
X553786Y-349894D01*
Y-350394D01*
X456302Y-349048D02*
Y-352047D01*
X457802D01*
X458301Y-351547D01*
Y-349548D01*
X457802Y-349048D01*
X456302D01*
X461301D02*
X460301Y-349548D01*
X459301Y-350548D01*
Y-351547D01*
X459801Y-352047D01*
X460801D01*
X461301Y-351547D01*
Y-351048D01*
X460801Y-350548D01*
X459301D01*
X410633Y-348655D02*
Y-351654D01*
X412132D01*
X412632Y-351154D01*
Y-349154D01*
X412132Y-348655D01*
X410633D01*
X415631D02*
X413632D01*
Y-350154D01*
X414632Y-349654D01*
X415131D01*
X415631Y-350154D01*
Y-351154D01*
X415131Y-351654D01*
X414132D01*
X413632Y-351154D01*
X82677Y-90702D02*
Y-93701D01*
X84177D01*
X84676Y-93201D01*
Y-91202D01*
X84177Y-90702D01*
X82677D01*
X87176Y-93701D02*
Y-90702D01*
X85676Y-92201D01*
X87675D01*
X247107Y-116505D02*
X246607Y-117004D01*
Y-118004D01*
X247107Y-118504D01*
X249107D01*
X249606Y-118004D01*
Y-117004D01*
X249107Y-116505D01*
X246607Y-113506D02*
X247107Y-114505D01*
X248107Y-115505D01*
X249107D01*
X249606Y-115005D01*
Y-114005D01*
X249107Y-113506D01*
X248607D01*
X248107Y-114005D01*
Y-115505D01*
X247107Y-112506D02*
X246607Y-112006D01*
Y-111006D01*
X247107Y-110506D01*
X247607D01*
X248107Y-111006D01*
Y-111506D01*
Y-111006D01*
X248607Y-110506D01*
X249107D01*
X249606Y-111006D01*
Y-112006D01*
X249107Y-112506D01*
X260158Y-108170D02*
X259659Y-107670D01*
X258659D01*
X258159Y-108170D01*
Y-110169D01*
X258659Y-110669D01*
X259659D01*
X260158Y-110169D01*
X263158Y-107670D02*
X262158Y-108170D01*
X261158Y-109170D01*
Y-110169D01*
X261658Y-110669D01*
X262658D01*
X263158Y-110169D01*
Y-109669D01*
X262658Y-109170D01*
X261158D01*
X266157Y-110669D02*
X264157D01*
X266157Y-108670D01*
Y-108170D01*
X265657Y-107670D01*
X264657D01*
X264157Y-108170D01*
X76241Y-72410D02*
X75741Y-72910D01*
Y-73910D01*
X76241Y-74410D01*
X78240D01*
X78740Y-73910D01*
Y-72910D01*
X78240Y-72410D01*
X78740Y-71410D02*
Y-70411D01*
Y-70911D01*
X75741D01*
X76241Y-71410D01*
X78740Y-67412D02*
X75741D01*
X77241Y-68911D01*
Y-66912D01*
X78771Y-53800D02*
X78271Y-53300D01*
X77271D01*
X76772Y-53800D01*
Y-55799D01*
X77271Y-56299D01*
X78271D01*
X78771Y-55799D01*
X79771Y-56299D02*
X80770D01*
X80270D01*
Y-53300D01*
X79771Y-53800D01*
X82270D02*
X82770Y-53300D01*
X83769D01*
X84269Y-53800D01*
Y-54300D01*
X83769Y-54800D01*
X83270D01*
X83769D01*
X84269Y-55300D01*
Y-55799D01*
X83769Y-56299D01*
X82770D01*
X82270Y-55799D01*
X16566Y-8918D02*
X16067Y-8418D01*
X15067D01*
X14567Y-8918D01*
Y-10917D01*
X15067Y-11417D01*
X16067D01*
X16566Y-10917D01*
X17566Y-11417D02*
X18566D01*
X18066D01*
Y-8418D01*
X17566Y-8918D01*
X22064Y-11417D02*
X20065D01*
X22064Y-9418D01*
Y-8918D01*
X21565Y-8418D01*
X20565D01*
X20065Y-8918D01*
X16960Y-17973D02*
X16460Y-17473D01*
X15461D01*
X14961Y-17973D01*
Y-19973D01*
X15461Y-20472D01*
X16460D01*
X16960Y-19973D01*
X17960Y-20472D02*
X18959D01*
X18460D01*
Y-17473D01*
X17960Y-17973D01*
X20459Y-20472D02*
X21459D01*
X20959D01*
Y-17473D01*
X20459Y-17973D01*
X40414Y10267D02*
X39914Y9767D01*
Y8768D01*
X40414Y8268D01*
X42413D01*
X42913Y8768D01*
Y9767D01*
X42413Y10267D01*
X42913Y11267D02*
Y12266D01*
Y11767D01*
X39914D01*
X40414Y11267D01*
Y13766D02*
X39914Y14266D01*
Y15266D01*
X40414Y15765D01*
X42413D01*
X42913Y15266D01*
Y14266D01*
X42413Y13766D01*
X40414D01*
X149350Y-94130D02*
X149849Y-93630D01*
Y-92631D01*
X149350Y-92131D01*
X147350D01*
X146850Y-92631D01*
Y-93630D01*
X147350Y-94130D01*
X149350Y-95130D02*
X149849Y-95630D01*
Y-96630D01*
X149350Y-97129D01*
X148850D01*
X148350Y-96630D01*
X147850Y-97129D01*
X147350D01*
X146850Y-96630D01*
Y-95630D01*
X147350Y-95130D01*
X147850D01*
X148350Y-95630D01*
X148850Y-95130D01*
X149350D01*
X148350Y-95630D02*
Y-96630D01*
X175334Y-101999D02*
X175834Y-101499D01*
Y-100500D01*
X175334Y-100000D01*
X173335D01*
X172835Y-100500D01*
Y-101499D01*
X173335Y-101999D01*
X175834Y-102999D02*
Y-104998D01*
X175334D01*
X173335Y-102999D01*
X172835D01*
X354398Y-164467D02*
X353899Y-163967D01*
X352899D01*
X352399Y-164467D01*
Y-166467D01*
X352899Y-166966D01*
X353899D01*
X354398Y-166467D01*
X356898Y-166966D02*
Y-163967D01*
X355398Y-165467D01*
X357398D01*
X610493Y-31859D02*
X609993Y-32359D01*
Y-33358D01*
X610493Y-33858D01*
X612492D01*
X612992Y-33358D01*
Y-32359D01*
X612492Y-31859D01*
X612992Y-28860D02*
Y-30859D01*
X610993Y-28860D01*
X610493D01*
X609993Y-29360D01*
Y-30359D01*
X610493Y-30859D01*
X619548Y-29890D02*
X619048Y-30390D01*
Y-31390D01*
X619548Y-31890D01*
X621547D01*
X622047Y-31390D01*
Y-30390D01*
X621547Y-29890D01*
X622047Y-28891D02*
Y-27891D01*
Y-28391D01*
X619048D01*
X619548Y-28891D01*
D25*
X549079Y-194840D02*
X548579Y-195340D01*
Y-196340D01*
X549079Y-196840D01*
X551078D01*
X551578Y-196340D01*
Y-195340D01*
X551078Y-194840D01*
X550078D01*
Y-195840D01*
X551578Y-193841D02*
X548579D01*
Y-192341D01*
X549079Y-191841D01*
X550078D01*
X550578Y-192341D01*
Y-193841D01*
X549079Y-188842D02*
X548579Y-189342D01*
Y-190342D01*
X549079Y-190842D01*
X549579D01*
X550078Y-190342D01*
Y-189342D01*
X550578Y-188842D01*
X551078D01*
X551578Y-189342D01*
Y-190342D01*
X551078Y-190842D01*
X551578Y-185843D02*
Y-187843D01*
X549579Y-185843D01*
X549079D01*
X548579Y-186343D01*
Y-187343D01*
X549079Y-187843D01*
Y-179845D02*
X548579Y-180345D01*
Y-181345D01*
X549079Y-181844D01*
X549579D01*
X550078Y-181345D01*
Y-180345D01*
X550578Y-179845D01*
X551078D01*
X551578Y-180345D01*
Y-181345D01*
X551078Y-181844D01*
X551578Y-177346D02*
Y-178346D01*
X551078Y-178846D01*
X550078D01*
X549579Y-178346D01*
Y-177346D01*
X550078Y-176846D01*
X550578D01*
Y-178846D01*
X551578Y-175847D02*
Y-174847D01*
Y-175347D01*
X548579D01*
Y-175847D01*
X551578Y-171848D02*
Y-172847D01*
X551078Y-173347D01*
X550078D01*
X549579Y-172847D01*
Y-171848D01*
X550078Y-171348D01*
X550578D01*
Y-173347D01*
X549579Y-168349D02*
Y-169848D01*
X550078Y-170348D01*
X551078D01*
X551578Y-169848D01*
Y-168349D01*
X549079Y-166849D02*
X549579D01*
Y-167349D01*
Y-166349D01*
Y-166849D01*
X551078D01*
X551578Y-166349D01*
X559380Y-187085D02*
X558880Y-187585D01*
Y-188585D01*
X559380Y-189085D01*
X561380D01*
X561879Y-188585D01*
Y-187585D01*
X561380Y-187085D01*
X560380D01*
Y-188085D01*
X561879Y-186085D02*
X558880D01*
Y-184586D01*
X559380Y-184086D01*
X560380D01*
X560880Y-184586D01*
Y-186085D01*
X559380Y-181087D02*
X558880Y-181587D01*
Y-182587D01*
X559380Y-183087D01*
X559880D01*
X560380Y-182587D01*
Y-181587D01*
X560880Y-181087D01*
X561380D01*
X561879Y-181587D01*
Y-182587D01*
X561380Y-183087D01*
X561879Y-180087D02*
Y-179088D01*
Y-179588D01*
X558880D01*
X559380Y-180087D01*
Y-172590D02*
X558880Y-173090D01*
Y-174089D01*
X559380Y-174589D01*
X559880D01*
X560380Y-174089D01*
Y-173090D01*
X560880Y-172590D01*
X561380D01*
X561879Y-173090D01*
Y-174089D01*
X561380Y-174589D01*
X561879Y-170091D02*
Y-171090D01*
X561380Y-171590D01*
X560380D01*
X559880Y-171090D01*
Y-170091D01*
X560380Y-169591D01*
X560880D01*
Y-171590D01*
X561879Y-168591D02*
Y-167592D01*
Y-168091D01*
X558880D01*
Y-168591D01*
X561879Y-164593D02*
Y-165592D01*
X561380Y-166092D01*
X560380D01*
X559880Y-165592D01*
Y-164593D01*
X560380Y-164093D01*
X560880D01*
Y-166092D01*
X559880Y-161094D02*
Y-162593D01*
X560380Y-163093D01*
X561380D01*
X561879Y-162593D01*
Y-161094D01*
X559380Y-159594D02*
X559880D01*
Y-160094D01*
Y-159094D01*
Y-159594D01*
X561380D01*
X561879Y-159094D01*
X512736Y-218960D02*
Y-219960D01*
X513236Y-220460D01*
X515236D01*
X515735Y-219960D01*
Y-218960D01*
X515236Y-218460D01*
X513236D01*
X512736Y-218960D01*
X513236Y-215461D02*
X512736Y-215961D01*
Y-216961D01*
X513236Y-217461D01*
X513736D01*
X514236Y-216961D01*
Y-215961D01*
X514736Y-215461D01*
X515236D01*
X515735Y-215961D01*
Y-216961D01*
X515236Y-217461D01*
X513236Y-212462D02*
X512736Y-212962D01*
Y-213962D01*
X513236Y-214462D01*
X515236D01*
X515735Y-213962D01*
Y-212962D01*
X515236Y-212462D01*
X513236Y-206464D02*
X512736Y-206964D01*
Y-207964D01*
X513236Y-208464D01*
X513736D01*
X514236Y-207964D01*
Y-206964D01*
X514736Y-206464D01*
X515236D01*
X515735Y-206964D01*
Y-207964D01*
X515236Y-208464D01*
X515735Y-203965D02*
Y-204965D01*
X515236Y-205465D01*
X514236D01*
X513736Y-204965D01*
Y-203965D01*
X514236Y-203465D01*
X514736D01*
Y-205465D01*
X513736Y-202466D02*
X515735D01*
X514736D01*
X514236Y-201966D01*
X513736Y-201466D01*
Y-200966D01*
X515735Y-199467D02*
Y-198467D01*
Y-198967D01*
X513736D01*
Y-199467D01*
Y-196468D02*
Y-195468D01*
X514236Y-194968D01*
X515735D01*
Y-196468D01*
X515236Y-196967D01*
X514736Y-196468D01*
Y-194968D01*
X515735Y-193968D02*
Y-192969D01*
Y-193469D01*
X512736D01*
Y-193968D01*
X513236Y-186471D02*
X512736Y-186971D01*
Y-187970D01*
X513236Y-188470D01*
X513736D01*
X514236Y-187970D01*
Y-186971D01*
X514736Y-186471D01*
X515236D01*
X515735Y-186971D01*
Y-187970D01*
X515236Y-188470D01*
X515735Y-183972D02*
Y-184971D01*
X515236Y-185471D01*
X514236D01*
X513736Y-184971D01*
Y-183972D01*
X514236Y-183472D01*
X514736D01*
Y-185471D01*
X515735Y-182472D02*
Y-181472D01*
Y-181972D01*
X512736D01*
Y-182472D01*
X515735Y-178473D02*
Y-179473D01*
X515236Y-179973D01*
X514236D01*
X513736Y-179473D01*
Y-178473D01*
X514236Y-177974D01*
X514736D01*
Y-179973D01*
X513736Y-174975D02*
Y-176474D01*
X514236Y-176974D01*
X515236D01*
X515735Y-176474D01*
Y-174975D01*
X513236Y-173475D02*
X513736D01*
Y-173975D01*
Y-172975D01*
Y-173475D01*
X515236D01*
X515735Y-172975D01*
X445127Y-27996D02*
X445627Y-28496D01*
Y-29495D01*
X445127Y-29995D01*
X444627D01*
X444127Y-29495D01*
Y-28996D01*
Y-29495D01*
X443627Y-29995D01*
X443127D01*
X442628Y-29495D01*
Y-28496D01*
X443127Y-27996D01*
X445127Y-30995D02*
X445627Y-31495D01*
Y-32495D01*
X445127Y-32994D01*
X443127D01*
X442628Y-32495D01*
Y-31495D01*
X443127Y-30995D01*
X445127D01*
X445627Y-35993D02*
X445127Y-34994D01*
X444127Y-33994D01*
X443127D01*
X442628Y-34494D01*
Y-35493D01*
X443127Y-35993D01*
X443627D01*
X444127Y-35493D01*
Y-33994D01*
X445127Y-36993D02*
X445627Y-37493D01*
Y-38493D01*
X445127Y-38992D01*
X443127D01*
X442628Y-38493D01*
Y-37493D01*
X443127Y-36993D01*
X445127D01*
X532327Y-92507D02*
X530328D01*
X532327Y-90508D01*
Y-90008D01*
X531827Y-89508D01*
X530827D01*
X530328Y-90008D01*
X535326Y-92507D02*
X533327D01*
X535326Y-90508D01*
Y-90008D01*
X534826Y-89508D01*
X533826D01*
X533327Y-90008D01*
X537825Y-92507D02*
Y-89508D01*
X536326Y-91008D01*
X538325D01*
X541324Y-92507D02*
X539325D01*
X541324Y-90508D01*
Y-90008D01*
X540824Y-89508D01*
X539824D01*
X539325Y-90008D01*
X345713Y-22428D02*
X343713D01*
X345713Y-20429D01*
Y-19929D01*
X345213Y-19429D01*
X344213D01*
X343713Y-19929D01*
X348712Y-22428D02*
X346712D01*
X348712Y-20429D01*
Y-19929D01*
X348212Y-19429D01*
X347212D01*
X346712Y-19929D01*
X351211Y-22428D02*
Y-19429D01*
X349711Y-20929D01*
X351711D01*
X354710Y-22428D02*
X352711D01*
X354710Y-20429D01*
Y-19929D01*
X354210Y-19429D01*
X353210D01*
X352711Y-19929D01*
X498349Y-228398D02*
X495350D01*
Y-226898D01*
X495850Y-226398D01*
X496849D01*
X497349Y-226898D01*
Y-228398D01*
X498349Y-225399D02*
X495350D01*
Y-223899D01*
X495850Y-223399D01*
X496849D01*
X497349Y-223899D01*
Y-225399D01*
X495850Y-220400D02*
X495350Y-220900D01*
Y-221900D01*
X495850Y-222400D01*
X496349D01*
X496849Y-221900D01*
Y-220900D01*
X497349Y-220400D01*
X497849D01*
X498349Y-220900D01*
Y-221900D01*
X497849Y-222400D01*
X495850Y-214402D02*
X495350Y-214902D01*
Y-215902D01*
X495850Y-216402D01*
X496349D01*
X496849Y-215902D01*
Y-214902D01*
X497349Y-214402D01*
X497849D01*
X498349Y-214902D01*
Y-215902D01*
X497849Y-216402D01*
X498349Y-211903D02*
Y-212903D01*
X497849Y-213403D01*
X496849D01*
X496349Y-212903D01*
Y-211903D01*
X496849Y-211403D01*
X497349D01*
Y-213403D01*
X498349Y-210404D02*
Y-209404D01*
Y-209904D01*
X495350D01*
Y-210404D01*
X498349Y-206405D02*
Y-207405D01*
X497849Y-207904D01*
X496849D01*
X496349Y-207405D01*
Y-206405D01*
X496849Y-205905D01*
X497349D01*
Y-207904D01*
X496349Y-202906D02*
Y-204406D01*
X496849Y-204905D01*
X497849D01*
X498349Y-204406D01*
Y-202906D01*
X495850Y-201407D02*
X496349D01*
Y-201906D01*
Y-200907D01*
Y-201407D01*
X497849D01*
X498349Y-200907D01*
X470610Y-238964D02*
X473110D01*
X473609Y-238464D01*
Y-237464D01*
X473110Y-236964D01*
X470610D01*
X473609Y-235965D02*
X471610D01*
X470610Y-234965D01*
X471610Y-233965D01*
X473609D01*
X472110D01*
Y-235965D01*
X473609Y-232966D02*
X470610D01*
Y-231466D01*
X471110Y-230966D01*
X472110D01*
X472610Y-231466D01*
Y-232966D01*
Y-231966D02*
X473609Y-230966D01*
X470610Y-229967D02*
Y-227967D01*
Y-228967D01*
X473609D01*
X471110Y-221969D02*
X470610Y-222469D01*
Y-223469D01*
X471110Y-223969D01*
X471610D01*
X472110Y-223469D01*
Y-222469D01*
X472610Y-221969D01*
X473110D01*
X473609Y-222469D01*
Y-223469D01*
X473110Y-223969D01*
X473609Y-219470D02*
Y-220470D01*
X473110Y-220970D01*
X472110D01*
X471610Y-220470D01*
Y-219470D01*
X472110Y-218970D01*
X472610D01*
Y-220970D01*
X473609Y-217971D02*
Y-216971D01*
Y-217471D01*
X470610D01*
Y-217971D01*
X473609Y-213972D02*
Y-214971D01*
X473110Y-215471D01*
X472110D01*
X471610Y-214971D01*
Y-213972D01*
X472110Y-213472D01*
X472610D01*
Y-215471D01*
X471610Y-210473D02*
Y-211972D01*
X472110Y-212472D01*
X473110D01*
X473609Y-211972D01*
Y-210473D01*
X471110Y-208974D02*
X471610D01*
Y-209473D01*
Y-208474D01*
Y-208974D01*
X473110D01*
X473609Y-208474D01*
X622447Y-88189D02*
Y-91521D01*
X621614D01*
X618282Y-88189D01*
X617449D01*
X606693Y-89764D02*
Y-91430D01*
Y-90597D01*
X611691D01*
X610858Y-89764D01*
X604605Y-143096D02*
X603772Y-141430D01*
X602106Y-139764D01*
X600439D01*
X599606Y-140597D01*
Y-142263D01*
X600439Y-143096D01*
X601272D01*
X602106Y-142263D01*
Y-139764D01*
X624449Y-144211D02*
Y-145877D01*
Y-145044D01*
X629447D01*
X628614Y-144211D01*
X624449Y-151708D02*
Y-148376D01*
X627781Y-151708D01*
X628614D01*
X629447Y-150875D01*
Y-149209D01*
X628614Y-148376D01*
X581760Y-145200D02*
Y-142201D01*
X583259D01*
X583759Y-142701D01*
Y-143701D01*
X583259Y-144201D01*
X581760D01*
X582759D02*
X583759Y-145200D01*
X584759D02*
X585758D01*
X585258D01*
Y-142201D01*
X584759Y-142701D01*
X587258Y-142201D02*
X589257D01*
Y-142701D01*
X587258Y-144701D01*
Y-145200D01*
X590257Y-144701D02*
X590757Y-145200D01*
X591756D01*
X592256Y-144701D01*
Y-142701D01*
X591756Y-142201D01*
X590757D01*
X590257Y-142701D01*
Y-143201D01*
X590757Y-143701D01*
X592256D01*
X581684Y-148894D02*
Y-151893D01*
X583184D01*
X583684Y-151393D01*
Y-149394D01*
X583184Y-148894D01*
X581684D01*
X584683Y-151893D02*
X585683D01*
X585183D01*
Y-148894D01*
X584683Y-149394D01*
X587183Y-151393D02*
X587682Y-151893D01*
X588682D01*
X589182Y-151393D01*
Y-149394D01*
X588682Y-148894D01*
X587682D01*
X587183Y-149394D01*
Y-149894D01*
X587682Y-150394D01*
X589182D01*
X583018Y-183890D02*
Y-186889D01*
X584518D01*
X585018Y-186389D01*
Y-184390D01*
X584518Y-183890D01*
X583018D01*
X586018Y-186889D02*
X587017D01*
X586517D01*
Y-183890D01*
X586018Y-184390D01*
X590516Y-186889D02*
X588517D01*
X590516Y-184889D01*
Y-184390D01*
X590016Y-183890D01*
X589016D01*
X588517Y-184390D01*
X140489Y11342D02*
Y8843D01*
X140989Y8343D01*
X141989D01*
X142489Y8843D01*
Y11342D01*
X145488Y8343D02*
X143489D01*
X145488Y10342D01*
Y10842D01*
X144988Y11342D01*
X143988D01*
X143489Y10842D01*
X146488Y8843D02*
X146987Y8343D01*
X147987D01*
X148487Y8843D01*
Y10842D01*
X147987Y11342D01*
X146987D01*
X146488Y10842D01*
Y10342D01*
X146987Y9843D01*
X148487D01*
X471995Y-287789D02*
Y-290288D01*
X472495Y-290788D01*
X473495D01*
X473994Y-290288D01*
Y-287789D01*
X476994Y-290788D02*
X474994D01*
X476994Y-288788D01*
Y-288288D01*
X476494Y-287789D01*
X475494D01*
X474994Y-288288D01*
X477993D02*
X478493Y-287789D01*
X479493D01*
X479993Y-288288D01*
Y-288788D01*
X479493Y-289288D01*
X479993Y-289788D01*
Y-290288D01*
X479493Y-290788D01*
X478493D01*
X477993Y-290288D01*
Y-289788D01*
X478493Y-289288D01*
X477993Y-288788D01*
Y-288288D01*
X478493Y-289288D02*
X479493D01*
X186265Y-86690D02*
Y-89189D01*
X186765Y-89688D01*
X187764D01*
X188264Y-89189D01*
Y-86690D01*
X189264Y-87189D02*
X189764Y-86690D01*
X190763D01*
X191263Y-87189D01*
Y-87689D01*
X190763Y-88189D01*
X190264D01*
X190763D01*
X191263Y-88689D01*
Y-89189D01*
X190763Y-89688D01*
X189764D01*
X189264Y-89189D01*
X192263Y-89688D02*
X193263D01*
X192763D01*
Y-86690D01*
X192263Y-87189D01*
X470203Y-261430D02*
X472702D01*
X473202Y-260930D01*
Y-259930D01*
X472702Y-259431D01*
X470203D01*
X470703Y-258431D02*
X470203Y-257931D01*
Y-256931D01*
X470703Y-256431D01*
X471203D01*
X471703Y-256931D01*
Y-257431D01*
Y-256931D01*
X472203Y-256431D01*
X472702D01*
X473202Y-256931D01*
Y-257931D01*
X472702Y-258431D01*
X470703Y-255432D02*
X470203Y-254932D01*
Y-253932D01*
X470703Y-253432D01*
X472702D01*
X473202Y-253932D01*
Y-254932D01*
X472702Y-255432D01*
X470703D01*
X203413Y-93625D02*
Y-90627D01*
X204913D01*
X205413Y-91126D01*
Y-92126D01*
X204913Y-92626D01*
X203413D01*
X204413D02*
X205413Y-93625D01*
X206412D02*
X207412D01*
X206912D01*
Y-90627D01*
X206412Y-91126D01*
X208911Y-90627D02*
X210911D01*
Y-91126D01*
X208911Y-93126D01*
Y-93625D01*
X211910Y-90627D02*
X213910D01*
Y-91126D01*
X211910Y-93126D01*
Y-93625D01*
X164830Y-93232D02*
Y-90233D01*
X166330D01*
X166830Y-90733D01*
Y-91732D01*
X166330Y-92232D01*
X164830D01*
X165830D02*
X166830Y-93232D01*
X167830D02*
X168829D01*
X168329D01*
Y-90233D01*
X167830Y-90733D01*
X170329Y-90233D02*
X172328D01*
Y-90733D01*
X170329Y-92732D01*
Y-93232D01*
X175327Y-90233D02*
X174327Y-90733D01*
X173328Y-91732D01*
Y-92732D01*
X173828Y-93232D01*
X174827D01*
X175327Y-92732D01*
Y-92232D01*
X174827Y-91732D01*
X173328D01*
X475909Y-285170D02*
X472910D01*
Y-283670D01*
X473410Y-283170D01*
X474409D01*
X474909Y-283670D01*
Y-285170D01*
Y-284170D02*
X475909Y-283170D01*
Y-282171D02*
Y-281171D01*
Y-281671D01*
X472910D01*
X473410Y-282171D01*
X472910Y-279671D02*
Y-277672D01*
X473410D01*
X475409Y-279671D01*
X475909D01*
X472910Y-274673D02*
Y-276672D01*
X474409D01*
X473910Y-275673D01*
Y-275173D01*
X474409Y-274673D01*
X475409D01*
X475909Y-275173D01*
Y-276172D01*
X475409Y-276672D01*
X204013Y-103852D02*
Y-100853D01*
X205513D01*
X206012Y-101353D01*
Y-102353D01*
X205513Y-102852D01*
X204013D01*
X205013D02*
X206012Y-103852D01*
X207012D02*
X208012D01*
X207512D01*
Y-100853D01*
X207012Y-101353D01*
X209511Y-100853D02*
X211511D01*
Y-101353D01*
X209511Y-103352D01*
Y-103852D01*
X214010D02*
Y-100853D01*
X212510Y-102353D01*
X214510D01*
X203413Y-88901D02*
Y-85902D01*
X204913D01*
X205413Y-86402D01*
Y-87402D01*
X204913Y-87901D01*
X203413D01*
X204413D02*
X205413Y-88901D01*
X206412D02*
X207412D01*
X206912D01*
Y-85902D01*
X206412Y-86402D01*
X208911Y-85902D02*
X210911D01*
Y-86402D01*
X208911Y-88401D01*
Y-88901D01*
X211910Y-86402D02*
X212410Y-85902D01*
X213410D01*
X213910Y-86402D01*
Y-86902D01*
X213410Y-87402D01*
X212910D01*
X213410D01*
X213910Y-87901D01*
Y-88401D01*
X213410Y-88901D01*
X212410D01*
X211910Y-88401D01*
X170342Y-97956D02*
Y-94957D01*
X171842D01*
X172342Y-95457D01*
Y-96457D01*
X171842Y-96956D01*
X170342D01*
X171342D02*
X172342Y-97956D01*
X173341D02*
X174341D01*
X173841D01*
Y-94957D01*
X173341Y-95457D01*
X175840Y-94957D02*
X177840D01*
Y-95457D01*
X175840Y-97456D01*
Y-97956D01*
X180839D02*
X178840D01*
X180839Y-95957D01*
Y-95457D01*
X180339Y-94957D01*
X179339D01*
X178840Y-95457D01*
X484570Y-251205D02*
X481571D01*
Y-249706D01*
X482071Y-249206D01*
X483071D01*
X483571Y-249706D01*
Y-251205D01*
Y-250205D02*
X484570Y-249206D01*
Y-248206D02*
Y-247206D01*
Y-247706D01*
X481571D01*
X482071Y-248206D01*
X481571Y-245707D02*
Y-243708D01*
X482071D01*
X484070Y-245707D01*
X484570D01*
Y-242708D02*
Y-241708D01*
Y-242208D01*
X481571D01*
X482071Y-242708D01*
X164830Y-88507D02*
Y-85508D01*
X166330D01*
X166830Y-86008D01*
Y-87008D01*
X166330Y-87508D01*
X164830D01*
X165830D02*
X166830Y-88507D01*
X167830D02*
X168829D01*
X168329D01*
Y-85508D01*
X167830Y-86008D01*
X170329Y-85508D02*
X172328D01*
Y-86008D01*
X170329Y-88007D01*
Y-88507D01*
X173328Y-86008D02*
X173828Y-85508D01*
X174827D01*
X175327Y-86008D01*
Y-88007D01*
X174827Y-88507D01*
X173828D01*
X173328Y-88007D01*
Y-86008D01*
X471972Y-285170D02*
X468973D01*
Y-283670D01*
X469473Y-283170D01*
X470472D01*
X470972Y-283670D01*
Y-285170D01*
Y-284170D02*
X471972Y-283170D01*
Y-282171D02*
Y-281171D01*
Y-281671D01*
X468973D01*
X469473Y-282171D01*
X468973Y-277672D02*
X469473Y-278672D01*
X470472Y-279671D01*
X471472D01*
X471972Y-279171D01*
Y-278172D01*
X471472Y-277672D01*
X470972D01*
X470472Y-278172D01*
Y-279671D01*
X471472Y-276672D02*
X471972Y-276172D01*
Y-275173D01*
X471472Y-274673D01*
X469473D01*
X468973Y-275173D01*
Y-276172D01*
X469473Y-276672D01*
X469973D01*
X470472Y-276172D01*
Y-274673D01*
X488901Y-274540D02*
X485902D01*
Y-273040D01*
X486402Y-272540D01*
X487402D01*
X487901Y-273040D01*
Y-274540D01*
Y-273540D02*
X488901Y-272540D01*
Y-271541D02*
Y-270541D01*
Y-271041D01*
X485902D01*
X486402Y-271541D01*
X485902Y-267042D02*
X486402Y-268042D01*
X487402Y-269041D01*
X488401D01*
X488901Y-268542D01*
Y-267542D01*
X488401Y-267042D01*
X487901D01*
X487402Y-267542D01*
Y-269041D01*
X486402Y-266042D02*
X485902Y-265543D01*
Y-264543D01*
X486402Y-264043D01*
X486902D01*
X487402Y-264543D01*
X487901Y-264043D01*
X488401D01*
X488901Y-264543D01*
Y-265543D01*
X488401Y-266042D01*
X487901D01*
X487402Y-265543D01*
X486902Y-266042D01*
X486402D01*
X487402Y-265543D02*
Y-264543D01*
X478665Y-251311D02*
X475666D01*
Y-249812D01*
X476166Y-249312D01*
X477165D01*
X477665Y-249812D01*
Y-251311D01*
Y-250312D02*
X478665Y-249312D01*
Y-248312D02*
Y-247313D01*
Y-247812D01*
X475666D01*
X476166Y-248312D01*
X475666Y-243814D02*
X476166Y-244813D01*
X477165Y-245813D01*
X478165D01*
X478665Y-245313D01*
Y-244314D01*
X478165Y-243814D01*
X477665D01*
X477165Y-244314D01*
Y-245813D01*
X475666Y-242814D02*
Y-240815D01*
X476166D01*
X478165Y-242814D01*
X478665D01*
X489688Y-251311D02*
X486690D01*
Y-249812D01*
X487189Y-249312D01*
X488189D01*
X488689Y-249812D01*
Y-251311D01*
Y-250312D02*
X489688Y-249312D01*
Y-248312D02*
Y-247313D01*
Y-247812D01*
X486690D01*
X487189Y-248312D01*
X486690Y-243814D02*
X487189Y-244813D01*
X488189Y-245813D01*
X489189D01*
X489688Y-245313D01*
Y-244314D01*
X489189Y-243814D01*
X488689D01*
X488189Y-244314D01*
Y-245813D01*
X486690Y-240815D02*
X487189Y-241814D01*
X488189Y-242814D01*
X489189D01*
X489688Y-242314D01*
Y-241315D01*
X489189Y-240815D01*
X488689D01*
X488189Y-241315D01*
Y-242814D01*
X200318Y5382D02*
X197319D01*
Y6881D01*
X197819Y7381D01*
X198819D01*
X199319Y6881D01*
Y5382D01*
Y6381D02*
X200318Y7381D01*
Y8381D02*
Y9380D01*
Y8880D01*
X197319D01*
X197819Y8381D01*
X197319Y12879D02*
X197819Y11880D01*
X198819Y10880D01*
X199819D01*
X200318Y11380D01*
Y12379D01*
X199819Y12879D01*
X199319D01*
X198819Y12379D01*
Y10880D01*
X197319Y15878D02*
Y13879D01*
X198819D01*
X198319Y14879D01*
Y15378D01*
X198819Y15878D01*
X199819D01*
X200318Y15378D01*
Y14379D01*
X199819Y13879D01*
X153619Y-16799D02*
X156618D01*
Y-18298D01*
X156118Y-18798D01*
X155118D01*
X154618Y-18298D01*
Y-16799D01*
Y-17799D02*
X153619Y-18798D01*
Y-19798D02*
Y-20798D01*
Y-20298D01*
X156618D01*
X156118Y-19798D01*
X156618Y-24296D02*
X156118Y-23297D01*
X155118Y-22297D01*
X154118D01*
X153619Y-22797D01*
Y-23797D01*
X154118Y-24296D01*
X154618D01*
X155118Y-23797D01*
Y-22297D01*
X153619Y-26796D02*
X156618D01*
X155118Y-25296D01*
Y-27296D01*
X120457Y-6396D02*
Y-3397D01*
X121957D01*
X122457Y-3897D01*
Y-4896D01*
X121957Y-5396D01*
X120457D01*
X121457D02*
X122457Y-6396D01*
X123456D02*
X124456D01*
X123956D01*
Y-3397D01*
X123456Y-3897D01*
X127955Y-3397D02*
X126955Y-3897D01*
X125955Y-4896D01*
Y-5896D01*
X126455Y-6396D01*
X127455D01*
X127955Y-5896D01*
Y-5396D01*
X127455Y-4896D01*
X125955D01*
X128954Y-3897D02*
X129454Y-3397D01*
X130454D01*
X130954Y-3897D01*
Y-4397D01*
X130454Y-4896D01*
X129954D01*
X130454D01*
X130954Y-5396D01*
Y-5896D01*
X130454Y-6396D01*
X129454D01*
X128954Y-5896D01*
X185751Y7744D02*
X182752D01*
Y9243D01*
X183252Y9743D01*
X184252D01*
X184752Y9243D01*
Y7744D01*
Y8743D02*
X185751Y9743D01*
Y10743D02*
Y11743D01*
Y11243D01*
X182752D01*
X183252Y10743D01*
X182752Y15241D02*
X183252Y14242D01*
X184252Y13242D01*
X185252D01*
X185751Y13742D01*
Y14742D01*
X185252Y15241D01*
X184752D01*
X184252Y14742D01*
Y13242D01*
X185751Y18240D02*
Y16241D01*
X183752Y18240D01*
X183252D01*
X182752Y17741D01*
Y16741D01*
X183252Y16241D01*
X191657Y5488D02*
X188658D01*
Y6987D01*
X189158Y7487D01*
X190157D01*
X190657Y6987D01*
Y5488D01*
Y6487D02*
X191657Y7487D01*
Y8487D02*
Y9487D01*
Y8987D01*
X188658D01*
X189158Y8487D01*
X188658Y12985D02*
X189158Y11986D01*
X190157Y10986D01*
X191157D01*
X191657Y11486D01*
Y12485D01*
X191157Y12985D01*
X190657D01*
X190157Y12485D01*
Y10986D01*
X191657Y13985D02*
Y14985D01*
Y14485D01*
X188658D01*
X189158Y13985D01*
X489240Y-301500D02*
Y-298500D01*
X490739D01*
X491239Y-299000D01*
Y-300000D01*
X490739Y-300500D01*
X489240D01*
X490240D02*
X491239Y-301500D01*
X492239D02*
X493239D01*
X492739D01*
Y-298500D01*
X492239Y-299000D01*
X496737Y-298500D02*
X495738Y-299000D01*
X494738Y-300000D01*
Y-301000D01*
X495238Y-301500D01*
X496238D01*
X496737Y-301000D01*
Y-300500D01*
X496238Y-300000D01*
X494738D01*
X497737Y-299000D02*
X498237Y-298500D01*
X499237D01*
X499736Y-299000D01*
Y-301000D01*
X499237Y-301500D01*
X498237D01*
X497737Y-301000D01*
Y-299000D01*
X161886Y-15224D02*
X164885D01*
Y-16724D01*
X164385Y-17223D01*
X163386D01*
X162886Y-16724D01*
Y-15224D01*
Y-16224D02*
X161886Y-17223D01*
Y-18223D02*
Y-19223D01*
Y-18723D01*
X164885D01*
X164385Y-18223D01*
X164885Y-22722D02*
Y-20722D01*
X163386D01*
X163886Y-21722D01*
Y-22222D01*
X163386Y-22722D01*
X162386D01*
X161886Y-22222D01*
Y-21222D01*
X162386Y-20722D01*
Y-23721D02*
X161886Y-24221D01*
Y-25221D01*
X162386Y-25721D01*
X164385D01*
X164885Y-25221D01*
Y-24221D01*
X164385Y-23721D01*
X163886D01*
X163386Y-24221D01*
Y-25721D01*
X486878Y-322759D02*
Y-319760D01*
X488377D01*
X488877Y-320260D01*
Y-321260D01*
X488377Y-321760D01*
X486878D01*
X487877D02*
X488877Y-322759D01*
X489877D02*
X490876D01*
X490377D01*
Y-319760D01*
X489877Y-320260D01*
X494375Y-319760D02*
X492376D01*
Y-321260D01*
X493376Y-320760D01*
X493875D01*
X494375Y-321260D01*
Y-322259D01*
X493875Y-322759D01*
X492876D01*
X492376Y-322259D01*
X495375Y-320260D02*
X495875Y-319760D01*
X496874D01*
X497374Y-320260D01*
Y-320760D01*
X496874Y-321260D01*
X497374Y-321760D01*
Y-322259D01*
X496874Y-322759D01*
X495875D01*
X495375Y-322259D01*
Y-321760D01*
X495875Y-321260D01*
X495375Y-320760D01*
Y-320260D01*
X495875Y-321260D02*
X496874D01*
X124830Y-15071D02*
Y-12071D01*
X126330D01*
X126830Y-12571D01*
Y-13571D01*
X126330Y-14071D01*
X124830D01*
X125830D02*
X126830Y-15071D01*
X127829D02*
X128829D01*
X128329D01*
Y-12071D01*
X127829Y-12571D01*
X132328Y-12071D02*
X130329D01*
Y-13571D01*
X131328Y-13071D01*
X131828D01*
X132328Y-13571D01*
Y-14571D01*
X131828Y-15071D01*
X130828D01*
X130329Y-14571D01*
X133327Y-12071D02*
X135327D01*
Y-12571D01*
X133327Y-14571D01*
Y-15071D01*
X458618Y-314634D02*
X461617D01*
Y-316133D01*
X461117Y-316633D01*
X460117D01*
X459618Y-316133D01*
Y-314634D01*
Y-315634D02*
X458618Y-316633D01*
Y-317633D02*
Y-318633D01*
Y-318133D01*
X461617D01*
X461117Y-317633D01*
X461617Y-322131D02*
Y-320132D01*
X460117D01*
X460617Y-321132D01*
Y-321632D01*
X460117Y-322131D01*
X459118D01*
X458618Y-321632D01*
Y-320632D01*
X459118Y-320132D01*
X461617Y-325131D02*
X461117Y-324131D01*
X460117Y-323131D01*
X459118D01*
X458618Y-323631D01*
Y-324631D01*
X459118Y-325131D01*
X459618D01*
X460117Y-324631D01*
Y-323131D01*
X176303Y7744D02*
X173304D01*
Y9243D01*
X173803Y9743D01*
X174803D01*
X175303Y9243D01*
Y7744D01*
Y8743D02*
X176303Y9743D01*
Y10743D02*
Y11743D01*
Y11243D01*
X173304D01*
X173803Y10743D01*
X173304Y15241D02*
Y13242D01*
X174803D01*
X174303Y14242D01*
Y14742D01*
X174803Y15241D01*
X175803D01*
X176303Y14742D01*
Y13742D01*
X175803Y13242D01*
X173304Y18240D02*
Y16241D01*
X174803D01*
X174303Y17241D01*
Y17741D01*
X174803Y18240D01*
X175803D01*
X176303Y17741D01*
Y16741D01*
X175803Y16241D01*
X468429Y-292650D02*
X465430D01*
Y-291150D01*
X465929Y-290651D01*
X466929D01*
X467429Y-291150D01*
Y-292650D01*
Y-291650D02*
X468429Y-290651D01*
Y-289651D02*
Y-288651D01*
Y-289151D01*
X465430D01*
X465929Y-289651D01*
X465430Y-285152D02*
Y-287152D01*
X466929D01*
X466429Y-286152D01*
Y-285652D01*
X466929Y-285152D01*
X467929D01*
X468429Y-285652D01*
Y-286652D01*
X467929Y-287152D01*
X468429Y-282653D02*
X465430D01*
X466929Y-284153D01*
Y-282153D01*
X477035Y-285752D02*
Y-282752D01*
X478535D01*
X479035Y-283252D01*
Y-284252D01*
X478535Y-284752D01*
X477035D01*
X478035D02*
X479035Y-285752D01*
X480034D02*
X481034D01*
X480534D01*
Y-282752D01*
X480034Y-283252D01*
X484533Y-282752D02*
X482533D01*
Y-284252D01*
X483533Y-283752D01*
X484033D01*
X484533Y-284252D01*
Y-285252D01*
X484033Y-285752D01*
X483033D01*
X482533Y-285252D01*
X485532Y-283252D02*
X486032Y-282752D01*
X487032D01*
X487532Y-283252D01*
Y-283752D01*
X487032Y-284252D01*
X486532D01*
X487032D01*
X487532Y-284752D01*
Y-285252D01*
X487032Y-285752D01*
X486032D01*
X485532Y-285252D01*
X120672Y-10913D02*
Y-7913D01*
X122172D01*
X122671Y-8413D01*
Y-9413D01*
X122172Y-9913D01*
X120672D01*
X121672D02*
X122671Y-10913D01*
X123671D02*
X124671D01*
X124171D01*
Y-7913D01*
X123671Y-8413D01*
X128170Y-7913D02*
X126170D01*
Y-9413D01*
X127170Y-8913D01*
X127670D01*
X128170Y-9413D01*
Y-10413D01*
X127670Y-10913D01*
X126670D01*
X126170Y-10413D01*
X131169Y-10913D02*
X129169D01*
X131169Y-8913D01*
Y-8413D01*
X130669Y-7913D01*
X129669D01*
X129169Y-8413D01*
X490977Y-308361D02*
Y-305361D01*
X492477D01*
X492977Y-305861D01*
Y-306861D01*
X492477Y-307361D01*
X490977D01*
X491977D02*
X492977Y-308361D01*
X493976D02*
X494976D01*
X494476D01*
Y-305361D01*
X493976Y-305861D01*
X498475Y-305361D02*
X496475D01*
Y-306861D01*
X497475Y-306361D01*
X497975D01*
X498475Y-306861D01*
Y-307861D01*
X497975Y-308361D01*
X496975D01*
X496475Y-307861D01*
X499474Y-308361D02*
X500474D01*
X499974D01*
Y-305361D01*
X499474Y-305861D01*
X157162Y-16012D02*
X160161D01*
Y-17511D01*
X159661Y-18011D01*
X158661D01*
X158162Y-17511D01*
Y-16012D01*
Y-17011D02*
X157162Y-18011D01*
Y-19011D02*
Y-20010D01*
Y-19510D01*
X160161D01*
X159661Y-19011D01*
X160161Y-23509D02*
Y-21510D01*
X158661D01*
X159161Y-22510D01*
Y-23009D01*
X158661Y-23509D01*
X157662D01*
X157162Y-23009D01*
Y-22010D01*
X157662Y-21510D01*
X159661Y-24509D02*
X160161Y-25009D01*
Y-26008D01*
X159661Y-26508D01*
X157662D01*
X157162Y-26008D01*
Y-25009D01*
X157662Y-24509D01*
X159661D01*
X469517Y-320255D02*
Y-317256D01*
X471017D01*
X471516Y-317756D01*
Y-318756D01*
X471017Y-319256D01*
X469517D01*
X470517D02*
X471516Y-320255D01*
X472516D02*
X473516D01*
X473016D01*
Y-317256D01*
X472516Y-317756D01*
X476515Y-320255D02*
Y-317256D01*
X475015Y-318756D01*
X477015D01*
X478014Y-319756D02*
X478514Y-320255D01*
X479514D01*
X480014Y-319756D01*
Y-317756D01*
X479514Y-317256D01*
X478514D01*
X478014Y-317756D01*
Y-318256D01*
X478514Y-318756D01*
X480014D01*
X463704Y-304855D02*
X460705D01*
Y-303355D01*
X461205Y-302855D01*
X462205D01*
X462705Y-303355D01*
Y-304855D01*
Y-303855D02*
X463704Y-302855D01*
Y-301856D02*
Y-300856D01*
Y-301356D01*
X460705D01*
X461205Y-301856D01*
X463704Y-297857D02*
X460705D01*
X462205Y-299356D01*
Y-297357D01*
X461205Y-296357D02*
X460705Y-295858D01*
Y-294858D01*
X461205Y-294358D01*
X461705D01*
X462205Y-294858D01*
X462705Y-294358D01*
X463204D01*
X463704Y-294858D01*
Y-295858D01*
X463204Y-296357D01*
X462705D01*
X462205Y-295858D01*
X461705Y-296357D01*
X461205D01*
X462205Y-295858D02*
Y-294858D01*
X195988Y5382D02*
X192989D01*
Y6881D01*
X193489Y7381D01*
X194488D01*
X194988Y6881D01*
Y5382D01*
Y6381D02*
X195988Y7381D01*
Y8381D02*
Y9380D01*
Y8880D01*
X192989D01*
X193489Y8381D01*
X195988Y12379D02*
X192989D01*
X194488Y10880D01*
Y12879D01*
X192989Y13879D02*
Y15878D01*
X193489D01*
X195488Y13879D01*
X195988D01*
X463461Y-314043D02*
X466460D01*
Y-315543D01*
X465960Y-316042D01*
X464961D01*
X464461Y-315543D01*
Y-314043D01*
Y-315043D02*
X463461Y-316042D01*
Y-317042D02*
Y-318042D01*
Y-317542D01*
X466460D01*
X465960Y-317042D01*
X463461Y-321041D02*
X466460D01*
X464961Y-319541D01*
Y-321541D01*
X466460Y-324540D02*
X465960Y-323540D01*
X464961Y-322540D01*
X463961D01*
X463461Y-323040D01*
Y-324040D01*
X463961Y-324540D01*
X464461D01*
X464961Y-324040D01*
Y-322540D01*
X491208Y-318822D02*
Y-315823D01*
X492708D01*
X493208Y-316323D01*
Y-317323D01*
X492708Y-317823D01*
X491208D01*
X492208D02*
X493208Y-318822D01*
X494207D02*
X495207D01*
X494707D01*
Y-315823D01*
X494207Y-316323D01*
X498206Y-318822D02*
Y-315823D01*
X496707Y-317323D01*
X498706D01*
X501705Y-315823D02*
X499706D01*
Y-317323D01*
X500705Y-316823D01*
X501205D01*
X501705Y-317323D01*
Y-318322D01*
X501205Y-318822D01*
X500206D01*
X499706Y-318322D01*
X181027Y7744D02*
X178028D01*
Y9243D01*
X178528Y9743D01*
X179527D01*
X180027Y9243D01*
Y7744D01*
Y8743D02*
X181027Y9743D01*
Y10743D02*
Y11743D01*
Y11243D01*
X178028D01*
X178528Y10743D01*
X181027Y14742D02*
X178028D01*
X179527Y13242D01*
Y15241D01*
X181027Y17741D02*
X178028D01*
X179527Y16241D01*
Y18240D01*
X490870Y-289894D02*
X487871D01*
Y-288394D01*
X488370Y-287895D01*
X489370D01*
X489870Y-288394D01*
Y-289894D01*
Y-288894D02*
X490870Y-287895D01*
Y-286895D02*
Y-285895D01*
Y-286395D01*
X487871D01*
X488370Y-286895D01*
X490870Y-282896D02*
X487871D01*
X489370Y-284396D01*
Y-282396D01*
X488370Y-281397D02*
X487871Y-280897D01*
Y-279897D01*
X488370Y-279397D01*
X488870D01*
X489370Y-279897D01*
Y-280397D01*
Y-279897D01*
X489870Y-279397D01*
X490370D01*
X490870Y-279897D01*
Y-280897D01*
X490370Y-281397D01*
X464517Y-293018D02*
X461518D01*
Y-291518D01*
X462018Y-291018D01*
X463018D01*
X463518Y-291518D01*
Y-293018D01*
Y-292018D02*
X464517Y-291018D01*
Y-290019D02*
Y-289019D01*
Y-289519D01*
X461518D01*
X462018Y-290019D01*
X464517Y-286020D02*
X461518D01*
X463018Y-287519D01*
Y-285520D01*
X464517Y-282521D02*
Y-284520D01*
X462518Y-282521D01*
X462018D01*
X461518Y-283021D01*
Y-284020D01*
X462018Y-284520D01*
X564830Y-302681D02*
Y-299682D01*
X566330D01*
X566830Y-300181D01*
Y-301181D01*
X566330Y-301681D01*
X564830D01*
X565830D02*
X566830Y-302681D01*
X567830D02*
X568829D01*
X568329D01*
Y-299682D01*
X567830Y-300181D01*
X570329D02*
X570828Y-299682D01*
X571828D01*
X572328Y-300181D01*
Y-300681D01*
X571828Y-301181D01*
X571328D01*
X571828D01*
X572328Y-301681D01*
Y-302181D01*
X571828Y-302681D01*
X570828D01*
X570329Y-302181D01*
X573328D02*
X573828Y-302681D01*
X574827D01*
X575327Y-302181D01*
Y-300181D01*
X574827Y-299682D01*
X573828D01*
X573328Y-300181D01*
Y-300681D01*
X573828Y-301181D01*
X575327D01*
X161886Y-61743D02*
X164885D01*
Y-63242D01*
X164385Y-63742D01*
X163386D01*
X162886Y-63242D01*
Y-61743D01*
Y-62742D02*
X161886Y-63742D01*
Y-64742D02*
Y-65741D01*
Y-65241D01*
X164885D01*
X164385Y-64742D01*
Y-67241D02*
X164885Y-67741D01*
Y-68740D01*
X164385Y-69240D01*
X163886D01*
X163386Y-68740D01*
Y-68241D01*
Y-68740D01*
X162886Y-69240D01*
X162386D01*
X161886Y-68740D01*
Y-67741D01*
X162386Y-67241D01*
X164385Y-70240D02*
X164885Y-70740D01*
Y-71739D01*
X164385Y-72239D01*
X163886D01*
X163386Y-71739D01*
X162886Y-72239D01*
X162386D01*
X161886Y-71739D01*
Y-70740D01*
X162386Y-70240D01*
X162886D01*
X163386Y-70740D01*
X163886Y-70240D01*
X164385D01*
X163386Y-70740D02*
Y-71739D01*
X553903Y-301327D02*
Y-298328D01*
X555402D01*
X555902Y-298828D01*
Y-299828D01*
X555402Y-300327D01*
X553903D01*
X554902D02*
X555902Y-301327D01*
X556902D02*
X557901D01*
X557402D01*
Y-298328D01*
X556902Y-298828D01*
X559401D02*
X559901Y-298328D01*
X560900D01*
X561400Y-298828D01*
Y-299328D01*
X560900Y-299828D01*
X560401D01*
X560900D01*
X561400Y-300327D01*
Y-300827D01*
X560900Y-301327D01*
X559901D01*
X559401Y-300827D01*
X562400Y-301327D02*
X563400D01*
X562900D01*
Y-298328D01*
X562400Y-298828D01*
X164492Y-50918D02*
X161493D01*
Y-49418D01*
X161993Y-48918D01*
X162992D01*
X163492Y-49418D01*
Y-50918D01*
Y-49918D02*
X164492Y-48918D01*
Y-47919D02*
Y-46919D01*
Y-47419D01*
X161493D01*
X161993Y-47919D01*
Y-45419D02*
X161493Y-44919D01*
Y-43920D01*
X161993Y-43420D01*
X162492D01*
X162992Y-43920D01*
Y-44420D01*
Y-43920D01*
X163492Y-43420D01*
X163992D01*
X164492Y-43920D01*
Y-44919D01*
X163992Y-45419D01*
X161993Y-42420D02*
X161493Y-41921D01*
Y-40921D01*
X161993Y-40421D01*
X163992D01*
X164492Y-40921D01*
Y-41921D01*
X163992Y-42420D01*
X161993D01*
X584177Y-269654D02*
Y-268654D01*
Y-269154D01*
X581677D01*
X581178Y-268654D01*
Y-268155D01*
X581677Y-267655D01*
X581178Y-272153D02*
X584177D01*
X582677Y-270654D01*
Y-272653D01*
X584177Y-275652D02*
Y-273653D01*
X582677D01*
X583177Y-274653D01*
Y-275152D01*
X582677Y-275652D01*
X581677D01*
X581178Y-275152D01*
Y-274153D01*
X581677Y-273653D01*
X216460Y-63749D02*
Y-62749D01*
Y-63249D01*
X213961D01*
X213461Y-62749D01*
Y-62249D01*
X213961Y-61749D01*
X213461Y-66248D02*
X216460D01*
X214961Y-64748D01*
Y-66748D01*
X213461Y-69247D02*
X216460D01*
X214961Y-67747D01*
Y-69747D01*
X467141Y-139339D02*
X467641Y-138839D01*
Y-137840D01*
X467141Y-137340D01*
X465142D01*
X464642Y-137840D01*
Y-138839D01*
X465142Y-139339D01*
X467641Y-140339D02*
Y-142338D01*
X467141D01*
X465142Y-140339D01*
X464642D01*
X467141Y-143338D02*
X467641Y-143838D01*
Y-144837D01*
X467141Y-145337D01*
X466642D01*
X466142Y-144837D01*
Y-144338D01*
Y-144837D01*
X465642Y-145337D01*
X465142D01*
X464642Y-144837D01*
Y-143838D01*
X465142Y-143338D01*
X77741Y2725D02*
X77241Y2225D01*
Y1225D01*
X77741Y726D01*
X79740D01*
X80240Y1225D01*
Y2225D01*
X79740Y2725D01*
X77241Y3725D02*
Y5724D01*
X77741D01*
X79740Y3725D01*
X80240D01*
Y8723D02*
Y6724D01*
X78240Y8723D01*
X77741D01*
X77241Y8223D01*
Y7224D01*
X77741Y6724D01*
X542989Y-20654D02*
X542489Y-20154D01*
X541489D01*
X540989Y-20654D01*
Y-22653D01*
X541489Y-23153D01*
X542489D01*
X542989Y-22653D01*
X543988Y-23153D02*
Y-20154D01*
X545488D01*
X545988Y-20654D01*
Y-21654D01*
X545488Y-22153D01*
X543988D01*
X544988D02*
X545988Y-23153D01*
X546987D02*
X547987D01*
X547487D01*
Y-20154D01*
X546987Y-20654D01*
X610721Y-218871D02*
X609722D01*
X610221D01*
Y-221370D01*
X609722Y-221870D01*
X609222D01*
X608722Y-221370D01*
X613221Y-221870D02*
Y-218871D01*
X611721Y-220371D01*
X613720D01*
X614720Y-219371D02*
X615220Y-218871D01*
X616220D01*
X616719Y-219371D01*
Y-219871D01*
X616220Y-220371D01*
X615720D01*
X616220D01*
X616719Y-220870D01*
Y-221370D01*
X616220Y-221870D01*
X615220D01*
X614720Y-221370D01*
X422218Y-97368D02*
Y-99867D01*
X422718Y-100367D01*
X423717D01*
X424217Y-99867D01*
Y-97368D01*
X427216Y-100367D02*
X425217D01*
X427216Y-98368D01*
Y-97868D01*
X426716Y-97368D01*
X425717D01*
X425217Y-97868D01*
X429715Y-100367D02*
Y-97368D01*
X428216Y-98868D01*
X430215D01*
X120791Y-18867D02*
X118292D01*
X117792Y-19367D01*
Y-20366D01*
X118292Y-20866D01*
X120791D01*
X117792Y-21866D02*
Y-22865D01*
Y-22366D01*
X120791D01*
X120291Y-21866D01*
X173916Y-125621D02*
X174416D01*
X175415Y-124622D01*
X174416Y-123622D01*
X173916D01*
X175415Y-124622D02*
X176915D01*
Y-122622D02*
Y-121623D01*
Y-122123D01*
X173916D01*
X174416Y-122622D01*
X375135Y-220941D02*
Y-223441D01*
X375635Y-223940D01*
X376635D01*
X377134Y-223441D01*
Y-220941D01*
X380134Y-223940D02*
X378134D01*
X380134Y-221941D01*
Y-221441D01*
X379634Y-220941D01*
X378634D01*
X378134Y-221441D01*
X381133Y-220941D02*
X383133D01*
Y-221441D01*
X381133Y-223441D01*
Y-223940D01*
X329860Y-229209D02*
Y-231708D01*
X330359Y-232208D01*
X331359D01*
X331859Y-231708D01*
Y-229209D01*
X334858Y-232208D02*
X332859D01*
X334858Y-230209D01*
Y-229709D01*
X334358Y-229209D01*
X333358D01*
X332859Y-229709D01*
X337857Y-229209D02*
X336857Y-229709D01*
X335858Y-230709D01*
Y-231708D01*
X336357Y-232208D01*
X337357D01*
X337857Y-231708D01*
Y-231208D01*
X337357Y-230709D01*
X335858D01*
X155450Y-93776D02*
Y-96275D01*
X155950Y-96775D01*
X156950D01*
X157449Y-96275D01*
Y-93776D01*
X160449Y-96775D02*
X158449D01*
X160449Y-94776D01*
Y-94276D01*
X159949Y-93776D01*
X158949D01*
X158449Y-94276D01*
X163447Y-93776D02*
X161448D01*
Y-95276D01*
X162448Y-94776D01*
X162948D01*
X163447Y-95276D01*
Y-96275D01*
X162948Y-96775D01*
X161948D01*
X161448Y-96275D01*
X621291Y-185645D02*
X621791Y-186145D01*
X622790D01*
X623290Y-185645D01*
Y-185145D01*
X622790Y-184646D01*
X621791D01*
X621291Y-184146D01*
Y-183646D01*
X621791Y-183146D01*
X622790D01*
X623290Y-183646D01*
X620291Y-186145D02*
Y-183146D01*
X619291Y-184146D01*
X618292Y-183146D01*
Y-186145D01*
X615293Y-183146D02*
X617292D01*
X615293Y-185145D01*
Y-185645D01*
X615793Y-186145D01*
X616792D01*
X617292Y-185645D01*
X356169Y-238507D02*
Y-235508D01*
X357668D01*
X358168Y-236008D01*
Y-237008D01*
X357668Y-237508D01*
X356169D01*
X357169D02*
X358168Y-238507D01*
X359168D02*
X360168D01*
X359668D01*
Y-235508D01*
X359168Y-236008D01*
X363667Y-238507D02*
X361667D01*
X363667Y-236508D01*
Y-236008D01*
X363167Y-235508D01*
X362167D01*
X361667Y-236008D01*
X364666D02*
X365166Y-235508D01*
X366166D01*
X366666Y-236008D01*
Y-236508D01*
X366166Y-237008D01*
X366666Y-237508D01*
Y-238007D01*
X366166Y-238507D01*
X365166D01*
X364666Y-238007D01*
Y-237508D01*
X365166Y-237008D01*
X364666Y-236508D01*
Y-236008D01*
X365166Y-237008D02*
X366166D01*
X356956Y-243625D02*
Y-240627D01*
X358456D01*
X358956Y-241126D01*
Y-242126D01*
X358456Y-242626D01*
X356956D01*
X357956D02*
X358956Y-243625D01*
X359956D02*
X360955D01*
X360455D01*
Y-240627D01*
X359956Y-241126D01*
X364454Y-243625D02*
X362455D01*
X364454Y-241626D01*
Y-241126D01*
X363954Y-240627D01*
X362954D01*
X362455Y-241126D01*
X365454Y-240627D02*
X367453D01*
Y-241126D01*
X365454Y-243126D01*
Y-243625D01*
X390837Y-214957D02*
Y-211958D01*
X392337D01*
X392836Y-212458D01*
Y-213458D01*
X392337Y-213958D01*
X390837D01*
X391837D02*
X392836Y-214957D01*
X393836D02*
X394836D01*
X394336D01*
Y-211958D01*
X393836Y-212458D01*
X398335Y-214957D02*
X396335D01*
X398335Y-212958D01*
Y-212458D01*
X397835Y-211958D01*
X396835D01*
X396335Y-212458D01*
X401334Y-211958D02*
X400334Y-212458D01*
X399334Y-213458D01*
Y-214458D01*
X399834Y-214957D01*
X400834D01*
X401334Y-214458D01*
Y-213958D01*
X400834Y-213458D01*
X399334D01*
X377823Y-214885D02*
Y-211886D01*
X379322D01*
X379822Y-212386D01*
Y-213386D01*
X379322Y-213886D01*
X377823D01*
X378822D02*
X379822Y-214885D01*
X380822D02*
X381821D01*
X381321D01*
Y-211886D01*
X380822Y-212386D01*
X385320Y-214885D02*
X383321D01*
X385320Y-212886D01*
Y-212386D01*
X384820Y-211886D01*
X383821D01*
X383321Y-212386D01*
X387819Y-214885D02*
Y-211886D01*
X386320Y-213386D01*
X388319D01*
X358137Y-218822D02*
Y-215823D01*
X359637D01*
X360137Y-216323D01*
Y-217323D01*
X359637Y-217823D01*
X358137D01*
X359137D02*
X360137Y-218822D01*
X361137D02*
X362136D01*
X361636D01*
Y-215823D01*
X361137Y-216323D01*
X365635Y-218822D02*
X363636D01*
X365635Y-216823D01*
Y-216323D01*
X365135Y-215823D01*
X364136D01*
X363636Y-216323D01*
X366635D02*
X367135Y-215823D01*
X368134D01*
X368634Y-216323D01*
Y-216823D01*
X368134Y-217323D01*
X367635D01*
X368134D01*
X368634Y-217823D01*
Y-218322D01*
X368134Y-218822D01*
X367135D01*
X366635Y-218322D01*
X378717Y-255882D02*
X381716D01*
Y-257381D01*
X381216Y-257881D01*
X380216D01*
X379716Y-257381D01*
Y-255882D01*
Y-256881D02*
X378717Y-257881D01*
Y-258880D02*
Y-259880D01*
Y-259380D01*
X381716D01*
X381216Y-258880D01*
X378717Y-263379D02*
Y-261380D01*
X380716Y-263379D01*
X381216D01*
X381716Y-262879D01*
Y-261879D01*
X381216Y-261380D01*
X378717Y-264379D02*
Y-265378D01*
Y-264879D01*
X381716D01*
X381216Y-264379D01*
X389730Y-255382D02*
X392729D01*
Y-256881D01*
X392229Y-257381D01*
X391229D01*
X390729Y-256881D01*
Y-255382D01*
Y-256381D02*
X389730Y-257381D01*
Y-258381D02*
Y-259380D01*
Y-258880D01*
X392729D01*
X392229Y-258381D01*
X389730Y-262879D02*
Y-260880D01*
X391729Y-262879D01*
X392229D01*
X392729Y-262379D01*
Y-261380D01*
X392229Y-260880D01*
Y-263879D02*
X392729Y-264379D01*
Y-265378D01*
X392229Y-265878D01*
X390230D01*
X389730Y-265378D01*
Y-264379D01*
X390230Y-263879D01*
X392229D01*
X384267Y-255632D02*
X387266D01*
Y-257131D01*
X386766Y-257631D01*
X385766D01*
X385266Y-257131D01*
Y-255632D01*
Y-256631D02*
X384267Y-257631D01*
Y-258631D02*
Y-259630D01*
Y-259130D01*
X387266D01*
X386766Y-258631D01*
X384267Y-261130D02*
Y-262129D01*
Y-261630D01*
X387266D01*
X386766Y-261130D01*
X384767Y-263629D02*
X384267Y-264129D01*
Y-265128D01*
X384767Y-265628D01*
X386766D01*
X387266Y-265128D01*
Y-264129D01*
X386766Y-263629D01*
X386266D01*
X385766Y-264129D01*
Y-265628D01*
X401003Y-255631D02*
X404002D01*
Y-257131D01*
X403502Y-257631D01*
X402503D01*
X402003Y-257131D01*
Y-255631D01*
Y-256631D02*
X401003Y-257631D01*
Y-258631D02*
Y-259630D01*
Y-259130D01*
X404002D01*
X403502Y-258631D01*
X401003Y-261130D02*
Y-262129D01*
Y-261630D01*
X404002D01*
X403502Y-261130D01*
Y-263629D02*
X404002Y-264129D01*
Y-265128D01*
X403502Y-265628D01*
X403002D01*
X402503Y-265128D01*
X402003Y-265628D01*
X401503D01*
X401003Y-265128D01*
Y-264129D01*
X401503Y-263629D01*
X402003D01*
X402503Y-264129D01*
X403002Y-263629D01*
X403502D01*
X402503Y-264129D02*
Y-265128D01*
X395280Y-255631D02*
X398279D01*
Y-257131D01*
X397779Y-257631D01*
X396779D01*
X396279Y-257131D01*
Y-255631D01*
Y-256631D02*
X395280Y-257631D01*
Y-258631D02*
Y-259630D01*
Y-259130D01*
X398279D01*
X397779Y-258631D01*
X395280Y-261130D02*
Y-262129D01*
Y-261630D01*
X398279D01*
X397779Y-261130D01*
X398279Y-263629D02*
Y-265628D01*
X397779D01*
X395779Y-263629D01*
X395280D01*
X412718Y-234570D02*
Y-231571D01*
X414218D01*
X414717Y-232071D01*
Y-233071D01*
X414218Y-233571D01*
X412718D01*
X413718D02*
X414717Y-234570D01*
X415717D02*
X416717D01*
X416217D01*
Y-231571D01*
X415717Y-232071D01*
X418216Y-234570D02*
X419216D01*
X418716D01*
Y-231571D01*
X418216Y-232071D01*
X422715Y-231571D02*
X421715Y-232071D01*
X420716Y-233071D01*
Y-234070D01*
X421215Y-234570D01*
X422215D01*
X422715Y-234070D01*
Y-233571D01*
X422215Y-233071D01*
X420716D01*
X411931Y-240082D02*
Y-237083D01*
X413430D01*
X413930Y-237583D01*
Y-238583D01*
X413430Y-239083D01*
X411931D01*
X412930D02*
X413930Y-240082D01*
X414930D02*
X415930D01*
X415430D01*
Y-237083D01*
X414930Y-237583D01*
X417429Y-240082D02*
X418429D01*
X417929D01*
Y-237083D01*
X417429Y-237583D01*
X421927Y-237083D02*
X419928D01*
Y-238583D01*
X420928Y-238083D01*
X421428D01*
X421927Y-238583D01*
Y-239582D01*
X421428Y-240082D01*
X420428D01*
X419928Y-239582D01*
X403663Y-216066D02*
Y-213067D01*
X405163D01*
X405662Y-213567D01*
Y-214567D01*
X405163Y-215067D01*
X403663D01*
X404663D02*
X405662Y-216066D01*
X406662D02*
X407662D01*
X407162D01*
Y-213067D01*
X406662Y-213567D01*
X409161Y-216066D02*
X410161D01*
X409661D01*
Y-213067D01*
X409161Y-213567D01*
X413160Y-216066D02*
Y-213067D01*
X411660Y-214567D01*
X413660D01*
X410750Y-225909D02*
Y-222910D01*
X412249D01*
X412749Y-223410D01*
Y-224409D01*
X412249Y-224909D01*
X410750D01*
X411749D02*
X412749Y-225909D01*
X413749D02*
X414748D01*
X414249D01*
Y-222910D01*
X413749Y-223410D01*
X416248Y-225909D02*
X417247D01*
X416748D01*
Y-222910D01*
X416248Y-223410D01*
X418747D02*
X419247Y-222910D01*
X420247D01*
X420746Y-223410D01*
Y-223910D01*
X420247Y-224409D01*
X419747D01*
X420247D01*
X420746Y-224909D01*
Y-225409D01*
X420247Y-225909D01*
X419247D01*
X418747Y-225409D01*
X299951Y-244298D02*
Y-241299D01*
X301451D01*
X301950Y-241798D01*
Y-242798D01*
X301451Y-243298D01*
X299951D01*
X300951D02*
X301950Y-244298D01*
X302950D02*
X303950D01*
X303450D01*
Y-241299D01*
X302950Y-241798D01*
X305449Y-244298D02*
X306449D01*
X305949D01*
Y-241299D01*
X305449Y-241798D01*
X307948Y-244298D02*
X308948D01*
X308448D01*
Y-241299D01*
X307948Y-241798D01*
X318609Y-114720D02*
Y-111721D01*
X320109D01*
X320608Y-112221D01*
Y-113220D01*
X320109Y-113720D01*
X318609D01*
X323607Y-111721D02*
X321608D01*
Y-113220D01*
X322608Y-112720D01*
X323108D01*
X323607Y-113220D01*
Y-114220D01*
X323108Y-114720D01*
X322108D01*
X321608Y-114220D01*
X595926Y-308586D02*
Y-305587D01*
X597426D01*
X597925Y-306087D01*
Y-307087D01*
X597426Y-307586D01*
X595926D01*
X600425Y-308586D02*
Y-305587D01*
X598925Y-307087D01*
X600924D01*
X187977Y-113023D02*
X187477Y-113523D01*
Y-114523D01*
X187977Y-115022D01*
X189976D01*
X190476Y-114523D01*
Y-113523D01*
X189976Y-113023D01*
X187977Y-112023D02*
X187477Y-111523D01*
Y-110524D01*
X187977Y-110024D01*
X188477D01*
X188976Y-110524D01*
Y-111024D01*
Y-110524D01*
X189476Y-110024D01*
X189976D01*
X190476Y-110524D01*
Y-111523D01*
X189976Y-112023D01*
Y-109024D02*
X190476Y-108524D01*
Y-107525D01*
X189976Y-107025D01*
X187977D01*
X187477Y-107525D01*
Y-108524D01*
X187977Y-109024D01*
X188477D01*
X188976Y-108524D01*
Y-107025D01*
D26*
X413779Y-15698D02*
D03*
D27*
Y-55954D02*
D03*
D28*
X519242Y-41535D02*
D03*
D29*
X10335Y-63927D02*
D03*
Y-108415D02*
D03*
D30*
X478986Y-41535D02*
D03*
M02*
